FILE_TYPE = MACRO_DRAWING;
SET COLOR_WIRE YELLOW;
SET COLOR_PROP MONO;
SET COLOR_DOT WHITE;
SET COLOR_ARC YELLOW;
SET COLOR_BODY GREEN;
SET COLOR_NOTE MONO;
SET PROP_DISPLAY VALUE;
SET PAGE_NUMBER P193;
FORCEADD VCC_CORE..1
(-3800 4700);
FORCEPROP 3 LASTPIN (-3800 4650) SIG_NAME PVCCMCP_CPU1\g
J 0
(-3790 4660);
DISPLAY 0.659574 (-3790 4660);
PAINT MONO (-3790 4660);
DISPLAY INVISIBLE (-3790 4660);
FORCEPROP 1 LAST HDL_POWER PVCCMCP_CPU1
J 1
(-3800 4750);
DISPLAY 0.617021 (-3800 4750);
PAINT GREEN (-3800 4750);
FORCEPROP 2 LAST CDS_LIB mstr_symbols
J 0
(-3800 4700);
PAINT MONO (-3800 4700);
DISPLAY INVISIBLE (-3800 4700);
FORCEPROP 1 LAST PATH I107
J 0
(-3750 4725);
DISPLAY 0.872340 (-3750 4725);
PAINT AQUA (-3750 4725);
DISPLAY INVISIBLE (-3750 4725);
FORCEADD OFFPAGE..4
(-5125 2675);
FORCEPROP 2 LAST $XR0 190 
J 0
(-4939 2675);
DISPLAY 0.638298 (-4939 2675);
PAINT MONO (-4939 2675);
FORCEPROP 2 LAST CDS_LIB mstr_standard
J 0
(-5125 2675);
PAINT MONO (-5125 2675);
DISPLAY INVISIBLE (-5125 2675);
FORCEPROP 2 LAST ROOM P0V95_FPGA_CPU0_VR
J 0
(-5675 2750);
DISPLAY 1.361702 (-5675 2750);
PAINT ORANGE (-5675 2750);
DISPLAY INVISIBLE (-5675 2750);
FORCEPROP 1 LAST OFFPAGE TRUE
J 0
(-4800 2550);
DISPLAY 0.872340 (-4800 2550);
PAINT GREEN (-4800 2550);
DISPLAY INVISIBLE (-4800 2550);
FORCEPROP 1 LAST COMMENT_BODY TRUE
J 0
(-5150 2575);
DISPLAY 0.872340 (-5150 2575);
PAINT GREEN (-5150 2575);
DISPLAY INVISIBLE (-5150 2575);
FORCEPROP 2 LAST PATH I111
J 0
(-4925 2725);
DISPLAY 1.021277 (-4925 2725);
PAINT ORANGE (-4925 2725);
DISPLAY INVISIBLE (-4925 2725);
FORCEADD OFFPAGE..2
(-5100 2625);
FORCEPROP 2 LAST $XR0 190 
J 0
(-4911 2625);
DISPLAY 0.638298 (-4911 2625);
PAINT MONO (-4911 2625);
FORCEPROP 2 LAST CDS_LIB mstr_standard
J 0
(-5100 2625);
PAINT MONO (-5100 2625);
DISPLAY INVISIBLE (-5100 2625);
FORCEPROP 2 LAST ROOM P0V95_FPGA_CPU0_VR
J 0
(-5525 2700);
DISPLAY 1.361702 (-5525 2700);
PAINT ORANGE (-5525 2700);
DISPLAY INVISIBLE (-5525 2700);
FORCEPROP 1 LAST OFFPAGE TRUE
J 0
(-4775 2500);
DISPLAY 1.170213 (-4775 2500);
PAINT GREEN (-4775 2500);
DISPLAY INVISIBLE (-4775 2500);
FORCEPROP 1 LAST COMMENT_BODY TRUE
J 0
(-5145 2530);
DISPLAY 1.170213 (-5145 2530);
PAINT GREEN (-5145 2530);
DISPLAY INVISIBLE (-5145 2530);
FORCEPROP 2 LAST PATH I112
J 0
(-4900 2675);
DISPLAY 1.021277 (-4900 2675);
PAINT ORANGE (-4900 2675);
DISPLAY INVISIBLE (-4900 2675);
FORCEADD OFFPAGE..4
(-5100 3025);
FORCEPROP 2 LAST $XR0 191 
J 0
(-4914 3025);
DISPLAY 0.638298 (-4914 3025);
PAINT MONO (-4914 3025);
FORCEPROP 2 LAST CDS_LIB mstr_standard
J 0
(-5100 3025);
PAINT MONO (-5100 3025);
DISPLAY INVISIBLE (-5100 3025);
FORCEPROP 2 LAST ROOM P0V95_FPGA_CPU0_VR
J 0
(-5650 3100);
DISPLAY 1.361702 (-5650 3100);
PAINT ORANGE (-5650 3100);
DISPLAY INVISIBLE (-5650 3100);
FORCEPROP 1 LAST OFFPAGE TRUE
J 0
(-4775 2900);
DISPLAY 0.872340 (-4775 2900);
PAINT GREEN (-4775 2900);
DISPLAY INVISIBLE (-4775 2900);
FORCEPROP 1 LAST COMMENT_BODY TRUE
J 0
(-5125 2925);
DISPLAY 0.872340 (-5125 2925);
PAINT GREEN (-5125 2925);
DISPLAY INVISIBLE (-5125 2925);
FORCEPROP 2 LAST PATH I113
J 0
(-4900 3075);
DISPLAY 1.021277 (-4900 3075);
PAINT ORANGE (-4900 3075);
DISPLAY INVISIBLE (-4900 3075);
FORCEADD OFFPAGE..2
(-5075 2975);
FORCEPROP 2 LAST $XR0 191 
J 0
(-4886 2975);
DISPLAY 0.638298 (-4886 2975);
PAINT MONO (-4886 2975);
FORCEPROP 2 LAST CDS_LIB mstr_standard
J 0
(-5075 2975);
PAINT MONO (-5075 2975);
DISPLAY INVISIBLE (-5075 2975);
FORCEPROP 2 LAST ROOM P0V95_FPGA_CPU0_VR
J 0
(-5500 3050);
DISPLAY 1.361702 (-5500 3050);
PAINT ORANGE (-5500 3050);
DISPLAY INVISIBLE (-5500 3050);
FORCEPROP 1 LAST OFFPAGE TRUE
J 0
(-4750 2850);
DISPLAY 1.170213 (-4750 2850);
PAINT GREEN (-4750 2850);
DISPLAY INVISIBLE (-4750 2850);
FORCEPROP 1 LAST COMMENT_BODY TRUE
J 0
(-5120 2880);
DISPLAY 1.170213 (-5120 2880);
PAINT GREEN (-5120 2880);
DISPLAY INVISIBLE (-5120 2880);
FORCEPROP 2 LAST PATH I114
J 0
(-4875 3025);
DISPLAY 1.021277 (-4875 3025);
PAINT ORANGE (-4875 3025);
DISPLAY INVISIBLE (-4875 3025);
FORCEADD VCC_CORE..1
(-4050 4650);
FORCEPROP 3 LASTPIN (-4050 4600) SIG_NAME P1V8_MCP_CPU1\g
J 0
(-4040 4610);
DISPLAY 0.659574 (-4040 4610);
PAINT MONO (-4040 4610);
DISPLAY INVISIBLE (-4040 4610);
FORCEPROP 1 LAST HDL_POWER P1V8_MCP_CPU1
J 1
(-4050 4700);
DISPLAY 0.617021 (-4050 4700);
PAINT GREEN (-4050 4700);
FORCEPROP 0 LAST VOLTAGE 1.8
J 0
(-4050 4800);
DISPLAY 1.021277 (-4050 4800);
PAINT SKYBLUE (-4050 4800);
DISPLAY INVISIBLE (-4050 4800);
FORCEPROP 2 LAST CDS_LIB mstr_symbols
J 0
(-4050 4650);
PAINT ORANGE (-4050 4650);
DISPLAY INVISIBLE (-4050 4650);
FORCEPROP 1 LAST PATH I131
J 0
(-4000 4675);
DISPLAY 0.872340 (-4000 4675);
PAINT AQUA (-4000 4675);
DISPLAY INVISIBLE (-4000 4675);
FORCEADD VCC_CORE..1
(-5250 3225);
FORCEPROP 3 LASTPIN (-5250 3175) SIG_NAME PVCCIOMCP_CPU1\g
J 0
(-5240 3185);
DISPLAY 0.659574 (-5240 3185);
PAINT MONO (-5240 3185);
DISPLAY INVISIBLE (-5240 3185);
FORCEPROP 1 LAST HDL_POWER PVCCIOMCP_CPU1
J 1
(-5250 3275);
DISPLAY 0.617021 (-5250 3275);
PAINT GREEN (-5250 3275);
FORCEPROP 0 LAST VOLTAGE +0.95
J 0
(-5250 3375);
DISPLAY 1.021277 (-5250 3375);
PAINT SKYBLUE (-5250 3375);
DISPLAY INVISIBLE (-5250 3375);
FORCEPROP 2 LAST CDS_LIB mstr_symbols
J 0
(-5250 3225);
PAINT ORANGE (-5250 3225);
DISPLAY INVISIBLE (-5250 3225);
FORCEPROP 1 LAST PATH I134
J 0
(-5200 3250);
DISPLAY 0.872340 (-5200 3250);
PAINT AQUA (-5200 3250);
DISPLAY INVISIBLE (-5200 3250);
FORCEADD OFFPAGE..2
(-5150 1625);
FORCEPROP 2 LAST $XR0 206 
J 0
(-4961 1625);
DISPLAY 0.638298 (-4961 1625);
PAINT MONO (-4961 1625);
FORCEPROP 2 LAST $XR1 213 
J 0
(-4841 1625);
DISPLAY 0.638298 (-4841 1625);
PAINT MONO (-4841 1625);
FORCEPROP 2 LAST $XR2 55 
J 0
(-4721 1625);
DISPLAY 0.638298 (-4721 1625);
PAINT MONO (-4721 1625);
FORCEPROP 2 LAST CDS_LIB mstr_standard
J 0
(-5150 1625);
PAINT ORANGE (-5150 1625);
DISPLAY INVISIBLE (-5150 1625);
FORCEPROP 2 LAST ROOM P0V95_FPGA_CPU0_VR
J 0
(-5575 1700);
DISPLAY 1.361702 (-5575 1700);
PAINT ORANGE (-5575 1700);
DISPLAY INVISIBLE (-5575 1700);
FORCEPROP 1 LAST OFFPAGE TRUE
J 0
(-4825 1500);
DISPLAY 1.170213 (-4825 1500);
PAINT GREEN (-4825 1500);
DISPLAY INVISIBLE (-4825 1500);
FORCEPROP 1 LAST COMMENT_BODY TRUE
J 0
(-5195 1530);
DISPLAY 1.170213 (-5195 1530);
PAINT GREEN (-5195 1530);
DISPLAY INVISIBLE (-5195 1530);
FORCEPROP 2 LAST PATH I138
J 0
(-4550 1675);
DISPLAY 1.021277 (-4550 1675);
PAINT ORANGE (-4550 1675);
DISPLAY INVISIBLE (-4550 1675);
FORCEADD CAP_A..1
(-1950 1875);
FORCEPROP 1 LAST LOCATION C3F1
J 0
(-1900 1975);
DISPLAY 0.617021 (-1900 1975);
PAINT AQUA (-1900 1975);
FORCEPROP 1 LAST PART_NUMBER 602433-106
J 0
(-1900 1725);
DISPLAY 0.617021 (-1900 1725);
PAINT BLUE (-1900 1725);
FORCEPROP 1 LAST VALUE 47UF
J 0
(-1900 1925);
DISPLAY 0.617021 (-1900 1925);
PAINT SKYBLUE (-1900 1925);
FORCEPROP 1 LAST TOLERANCE 20%
J 0
(-1900 1825);
DISPLAY 0.617021 (-1900 1825);
PAINT SKYBLUE (-1900 1825);
FORCEPROP 1 LAST PACK_TYPE 0603V
J 0
(-1900 1675);
DISPLAY 0.617021 (-1900 1675);
PAINT SKYBLUE (-1900 1675);
FORCEPROP 1 LAST VOLTAGE 4V
J 0
(-1900 1875);
DISPLAY 0.617021 (-1900 1875);
PAINT SKYBLUE (-1900 1875);
FORCEPROP 1 LAST MATERIAL X5R
J 0
(-1900 1775);
DISPLAY 0.617021 (-1900 1775);
PAINT SKYBLUE (-1900 1775);
FORCEPROP 1 LASTPIN (-1950 1975) $PN 1
J 0
(-1940 1955);
DISPLAY 0.617021 (-1940 1955);
PAINT ORANGE (-1940 1955);
FORCEPROP 1 LASTPIN (-1950 1775) $PN 2
J 0
(-1940 1755);
DISPLAY 0.617021 (-1940 1755);
PAINT ORANGE (-1940 1755);
FORCEPROP 2 LAST CDS_LOCATION C3F1
J 0
(-1900 1975);
DISPLAY 0.617021 (-1900 1975);
PAINT AQUA (-1900 1975);
DISPLAY INVISIBLE (-1900 1975);
FORCEPROP 2 LAST CDS_LIB dev_discrete
J 0
(-1950 1875);
PAINT ORANGE (-1950 1875);
DISPLAY INVISIBLE (-1950 1875);
FORCEPROP 2 LAST CDS_SEC 1
J 0
(-1900 2025);
PAINT ORANGE (-1900 2025);
DISPLAY INVISIBLE (-1900 2025);
FORCEPROP 2 LAST SEC_TYPE 0603V
J 0
(-1900 2075);
DISPLAY 1.021277 (-1900 2075);
PAINT ORANGE (-1900 2075);
DISPLAY INVISIBLE (-1900 2075);
FORCEPROP 2 LAST SEC 1
J 0
(-1900 2075);
PAINT MONO (-1900 2075);
DISPLAY INVISIBLE (-1900 2075);
FORCEPROP 1 LAST PATH I140
J 0
(-1900 2025);
DISPLAY 0.978723 (-1900 2025);
PAINT WHITE (-1900 2025);
DISPLAY INVISIBLE (-1900 2025);
FORCEADD CAP_A..1
(-1700 1875);
FORCEPROP 1 LAST LOCATION C4F2
J 0
(-1650 1975);
DISPLAY 0.617021 (-1650 1975);
PAINT AQUA (-1650 1975);
FORCEPROP 1 LAST PART_NUMBER 602433-106
J 0
(-1650 1725);
DISPLAY 0.617021 (-1650 1725);
PAINT BLUE (-1650 1725);
FORCEPROP 1 LAST VALUE 47UF
J 0
(-1650 1925);
DISPLAY 0.617021 (-1650 1925);
PAINT SKYBLUE (-1650 1925);
FORCEPROP 1 LAST TOLERANCE 20%
J 0
(-1650 1825);
DISPLAY 0.617021 (-1650 1825);
PAINT SKYBLUE (-1650 1825);
FORCEPROP 1 LAST PACK_TYPE 0603V
J 0
(-1650 1675);
DISPLAY 0.617021 (-1650 1675);
PAINT SKYBLUE (-1650 1675);
FORCEPROP 1 LAST VOLTAGE 4V
J 0
(-1650 1875);
DISPLAY 0.617021 (-1650 1875);
PAINT SKYBLUE (-1650 1875);
FORCEPROP 1 LAST MATERIAL X5R
J 0
(-1650 1775);
DISPLAY 0.617021 (-1650 1775);
PAINT SKYBLUE (-1650 1775);
FORCEPROP 1 LASTPIN (-1700 1975) $PN 1
J 0
(-1690 1955);
DISPLAY 0.617021 (-1690 1955);
PAINT ORANGE (-1690 1955);
FORCEPROP 1 LASTPIN (-1700 1775) $PN 2
J 0
(-1690 1755);
DISPLAY 0.617021 (-1690 1755);
PAINT ORANGE (-1690 1755);
FORCEPROP 2 LAST CDS_LOCATION C4F2
J 0
(-1650 1975);
DISPLAY 0.617021 (-1650 1975);
PAINT AQUA (-1650 1975);
DISPLAY INVISIBLE (-1650 1975);
FORCEPROP 2 LAST CDS_LIB dev_discrete
J 0
(-1700 1875);
PAINT ORANGE (-1700 1875);
DISPLAY INVISIBLE (-1700 1875);
FORCEPROP 2 LAST CDS_SEC 1
J 0
(-1650 2025);
PAINT ORANGE (-1650 2025);
DISPLAY INVISIBLE (-1650 2025);
FORCEPROP 2 LAST SEC_TYPE 0603V
J 0
(-1650 2075);
DISPLAY 1.021277 (-1650 2075);
PAINT ORANGE (-1650 2075);
DISPLAY INVISIBLE (-1650 2075);
FORCEPROP 2 LAST SEC 1
J 0
(-1650 2075);
PAINT MONO (-1650 2075);
DISPLAY INVISIBLE (-1650 2075);
FORCEPROP 1 LAST PATH I141
J 0
(-1650 2025);
DISPLAY 0.978723 (-1650 2025);
PAINT WHITE (-1650 2025);
DISPLAY INVISIBLE (-1650 2025);
FORCEADD PVCCIO_CPU1..1
(-7225 4575);
FORCEPROP 3 LASTPIN (-7225 4525) SIG_NAME PVCCIO_CPU1\g
J 0
(-7215 4535);
DISPLAY 0.659574 (-7215 4535);
PAINT MONO (-7215 4535);
DISPLAY INVISIBLE (-7215 4535);
FORCEPROP 1 LAST VOLTAGE 1.1V
J 0
(-7270 4532);
DISPLAY 0.340426 (-7270 4532);
PAINT SKYBLUE (-7270 4532);
DISPLAY INVISIBLE (-7270 4532);
FORCEPROP 2 LAST CDS_LIB mstr_symbols
J 0
(-7225 4575);
PAINT ORANGE (-7225 4575);
DISPLAY INVISIBLE (-7225 4575);
FORCEPROP 2 LAST BOM_COST PROC_VRD_PVCCIO_CPU1
J 0
(-7225 4675);
DISPLAY 2.340426 (-7225 4675);
PAINT WHITE (-7225 4675);
DISPLAY INVISIBLE (-7225 4675);
FORCEPROP 1 LAST BODY_TYPE PLUMBING
J 0
(-7270 4532);
DISPLAY 0.340426 (-7270 4532);
PAINT GREEN (-7270 4532);
DISPLAY INVISIBLE (-7270 4532);
FORCEPROP 1 LAST PATH I144
J 0
(-7175 4600);
DISPLAY 0.872340 (-7175 4600);
PAINT AQUA (-7175 4600);
DISPLAY INVISIBLE (-7175 4600);
FORCEPROP 2 LAST ROOM PVCCIO_CPU1
J 0
(-7225 4675);
DISPLAY 3.127660 (-7225 4675);
PAINT WHITE (-7225 4675);
DISPLAY INVISIBLE (-7225 4675);
FORCEPROP 1 LAST HDL_POWER PVCCIO_CPU1
J 1
(-7225 4625);
DISPLAY 0.872340 (-7225 4625);
PAINT GREEN (-7225 4625);
DISPLAY INVISIBLE (-7225 4625);
FORCEADD OFFPAGE..5
(-4775 2850);
FORCEPROP 2 LAST $XR0 104 
J 0
(-5030 2850);
DISPLAY 0.638298 (-5030 2850);
PAINT MONO (-5030 2850);
FORCEPROP 2 LAST BOM_COST PROC_VRD_VCCIN_CPU0
J 0
(-4450 2900);
PAINT MONO (-4450 2900);
DISPLAY INVISIBLE (-4450 2900);
FORCEPROP 2 LAST ROOM PVSA_CPU0_VSENSE_VR
J 0
(-5175 2925);
PAINT ORANGE (-5175 2925);
DISPLAY INVISIBLE (-5175 2925);
FORCEPROP 2 LAST CDS_LIB mstr_standard
J 0
(-4775 2850);
PAINT ORANGE (-4775 2850);
DISPLAY INVISIBLE (-4775 2850);
FORCEPROP 1 LAST OFFPAGE TRUE
J 0
(-4450 2725);
DISPLAY 0.872340 (-4450 2725);
PAINT GREEN (-4450 2725);
DISPLAY INVISIBLE (-4450 2725);
FORCEPROP 1 LAST COMMENT_BODY TRUE
J 0
(-4675 2775);
DISPLAY 0.872340 (-4675 2775);
PAINT GREEN (-4675 2775);
DISPLAY INVISIBLE (-4675 2775);
FORCEPROP 2 LAST PATH I149
J 0
(-4725 2925);
DISPLAY 1.021277 (-4725 2925);
PAINT ORANGE (-4725 2925);
DISPLAY INVISIBLE (-4725 2925);
FORCEADD OFFPAGE..5
(-4775 2900);
FORCEPROP 2 LAST $XR0 104 
J 0
(-5030 2900);
DISPLAY 0.638298 (-5030 2900);
PAINT MONO (-5030 2900);
FORCEPROP 2 LAST CDS_LIB mstr_standard
J 0
(-4775 2900);
PAINT ORANGE (-4775 2900);
DISPLAY INVISIBLE (-4775 2900);
FORCEPROP 2 LAST ROOM PVSA_CPU0_VSENSE_VR
J 0
(-5175 2975);
PAINT ORANGE (-5175 2975);
DISPLAY INVISIBLE (-5175 2975);
FORCEPROP 2 LAST BOM_COST PROC_VRD_VCCIN_CPU0
J 0
(-4450 2950);
PAINT MONO (-4450 2950);
DISPLAY INVISIBLE (-4450 2950);
FORCEPROP 1 LAST OFFPAGE TRUE
J 0
(-4450 2775);
DISPLAY 0.872340 (-4450 2775);
PAINT GREEN (-4450 2775);
DISPLAY INVISIBLE (-4450 2775);
FORCEPROP 1 LAST COMMENT_BODY TRUE
J 0
(-4675 2825);
DISPLAY 0.872340 (-4675 2825);
PAINT GREEN (-4675 2825);
DISPLAY INVISIBLE (-4675 2825);
FORCEPROP 2 LAST PATH I150
J 0
(-4725 2975);
DISPLAY 1.021277 (-4725 2975);
PAINT ORANGE (-4725 2975);
DISPLAY INVISIBLE (-4725 2975);
FORCEADD OFFPAGE..1
(-4825 4350);
FORCEPROP 2 LAST $XR0 56 
J 0
(-5046 4350);
DISPLAY 0.638298 (-5046 4350);
PAINT MONO (-5046 4350);
FORCEPROP 2 LAST CDS_LIB mstr_standard
J 0
(-4825 4350);
PAINT ORANGE (-4825 4350);
DISPLAY INVISIBLE (-4825 4350);
FORCEPROP 1 LAST OFFPAGE TRUE
J 0
(-4500 4225);
DISPLAY 1.170213 (-4500 4225);
PAINT GREEN (-4500 4225);
DISPLAY INVISIBLE (-4500 4225);
FORCEPROP 1 LAST COMMENT_BODY TRUE
J 0
(-4700 4250);
DISPLAY 1.170213 (-4700 4250);
PAINT GREEN (-4700 4250);
DISPLAY INVISIBLE (-4700 4250);
FORCEPROP 2 LAST PATH I151
J 0
(-4775 4425);
DISPLAY 1.021277 (-4775 4425);
PAINT ORANGE (-4775 4425);
DISPLAY INVISIBLE (-4775 4425);
FORCEADD OFFPAGE..1
(-4775 4000);
FORCEPROP 2 LAST $XR0 56 
J 0
(-5026 4000);
DISPLAY 0.638298 (-5026 4000);
PAINT MONO (-5026 4000);
FORCEPROP 2 LAST CDS_LIB mstr_standard
J 0
(-4775 4000);
PAINT ORANGE (-4775 4000);
DISPLAY INVISIBLE (-4775 4000);
FORCEPROP 1 LAST OFFPAGE TRUE
J 0
(-4450 3875);
DISPLAY 1.170213 (-4450 3875);
PAINT GREEN (-4450 3875);
DISPLAY INVISIBLE (-4450 3875);
FORCEPROP 1 LAST COMMENT_BODY TRUE
J 0
(-4650 3900);
DISPLAY 1.170213 (-4650 3900);
PAINT GREEN (-4650 3900);
DISPLAY INVISIBLE (-4650 3900);
FORCEPROP 2 LAST PATH I152
J 0
(-4725 4075);
DISPLAY 1.021277 (-4725 4075);
PAINT ORANGE (-4725 4075);
DISPLAY INVISIBLE (-4725 4075);
FORCEADD OFFPAGE..4
(-5100 1075);
FORCEPROP 2 LAST $XR0 55 
J 0
(-4884 1075);
DISPLAY 0.638298 (-4884 1075);
PAINT MONO (-4884 1075);
FORCEPROP 2 LAST $XR1 223 
J 0
(-4794 1075);
DISPLAY 0.638298 (-4794 1075);
PAINT MONO (-4794 1075);
FORCEPROP 2 LAST $XR2 226 
J 0
(-4674 1075);
DISPLAY 0.638298 (-4674 1075);
PAINT MONO (-4674 1075);
FORCEPROP 2 LAST CDS_LIB mstr_standard
J 0
(-5100 1075);
PAINT MONO (-5100 1075);
DISPLAY INVISIBLE (-5100 1075);
FORCEPROP 2 LAST ROOM P0V95_FPGA_CPU0_VR
J 0
(-5650 1150);
DISPLAY 1.361702 (-5650 1150);
PAINT ORANGE (-5650 1150);
DISPLAY INVISIBLE (-5650 1150);
FORCEPROP 1 LAST OFFPAGE TRUE
J 0
(-4775 950);
DISPLAY 0.872340 (-4775 950);
PAINT GREEN (-4775 950);
DISPLAY INVISIBLE (-4775 950);
FORCEPROP 1 LAST COMMENT_BODY TRUE
J 0
(-5125 975);
DISPLAY 0.872340 (-5125 975);
PAINT GREEN (-5125 975);
DISPLAY INVISIBLE (-5125 975);
FORCEPROP 2 LAST PATH I153
J 0
(-4700 1125);
DISPLAY 1.021277 (-4700 1125);
PAINT ORANGE (-4700 1125);
DISPLAY INVISIBLE (-4700 1125);
FORCEADD OFFPAGE..3
(-5100 1025);
FORCEPROP 2 LAST $XR0 55 
J 0
(-4886 1025);
DISPLAY 0.638298 (-4886 1025);
PAINT MONO (-4886 1025);
FORCEPROP 2 LAST $XR1 223 
J 0
(-4796 1025);
DISPLAY 0.638298 (-4796 1025);
PAINT MONO (-4796 1025);
FORCEPROP 2 LAST $XR2 226 
J 0
(-4676 1025);
DISPLAY 0.638298 (-4676 1025);
PAINT MONO (-4676 1025);
FORCEPROP 2 LAST CDS_LIB mstr_standard
J 0
(-5100 1025);
PAINT ORANGE (-5100 1025);
DISPLAY INVISIBLE (-5100 1025);
FORCEPROP 2 LAST ROOM P0V95_FPGA_CPU0_VR
J 0
(-5500 1100);
DISPLAY 1.361702 (-5500 1100);
PAINT ORANGE (-5500 1100);
DISPLAY INVISIBLE (-5500 1100);
FORCEPROP 1 LAST OFFPAGE TRUE
J 0
(-4775 900);
DISPLAY 1.170213 (-4775 900);
PAINT GREEN (-4775 900);
DISPLAY INVISIBLE (-4775 900);
FORCEPROP 1 LAST COMMENT_BODY TRUE
J 0
(-5150 925);
DISPLAY 1.170213 (-5150 925);
PAINT GREEN (-5150 925);
DISPLAY INVISIBLE (-5150 925);
FORCEPROP 2 LAST PATH I154
J 0
(-4675 1075);
DISPLAY 1.021277 (-4675 1075);
PAINT ORANGE (-4675 1075);
DISPLAY INVISIBLE (-4675 1075);
FORCEADD OFFPAGE..4
(-5075 1175);
FORCEPROP 2 LAST $XR0 190 
J 0
(-4889 1175);
DISPLAY 0.638298 (-4889 1175);
PAINT MONO (-4889 1175);
FORCEPROP 2 LAST ROOM P0V95_FPGA_CPU0_VR
J 0
(-5625 1250);
DISPLAY 1.361702 (-5625 1250);
PAINT ORANGE (-5625 1250);
DISPLAY INVISIBLE (-5625 1250);
FORCEPROP 2 LAST CDS_LIB mstr_standard
J 0
(-5075 1175);
PAINT ORANGE (-5075 1175);
DISPLAY INVISIBLE (-5075 1175);
FORCEPROP 1 LAST OFFPAGE TRUE
J 0
(-4750 1050);
DISPLAY 0.872340 (-4750 1050);
PAINT GREEN (-4750 1050);
DISPLAY INVISIBLE (-4750 1050);
FORCEPROP 1 LAST COMMENT_BODY TRUE
J 0
(-5100 1075);
DISPLAY 0.872340 (-5100 1075);
PAINT GREEN (-5100 1075);
DISPLAY INVISIBLE (-5100 1075);
FORCEPROP 2 LAST PATH I155
J 0
(-4900 1250);
DISPLAY 1.021277 (-4900 1250);
PAINT ORANGE (-4900 1250);
DISPLAY INVISIBLE (-4900 1250);
FORCEADD OFFPAGE..2
(-5075 1125);
FORCEPROP 2 LAST $XR0 190 
J 0
(-4886 1125);
DISPLAY 0.638298 (-4886 1125);
PAINT MONO (-4886 1125);
FORCEPROP 2 LAST ROOM P0V95_FPGA_CPU0_VR
J 0
(-5500 1200);
DISPLAY 1.361702 (-5500 1200);
PAINT ORANGE (-5500 1200);
DISPLAY INVISIBLE (-5500 1200);
FORCEPROP 2 LAST CDS_LIB mstr_standard
J 0
(-5075 1125);
PAINT ORANGE (-5075 1125);
DISPLAY INVISIBLE (-5075 1125);
FORCEPROP 1 LAST OFFPAGE TRUE
J 0
(-4750 1000);
DISPLAY 1.170213 (-4750 1000);
PAINT GREEN (-4750 1000);
DISPLAY INVISIBLE (-4750 1000);
FORCEPROP 1 LAST COMMENT_BODY TRUE
J 0
(-5120 1030);
DISPLAY 1.170213 (-5120 1030);
PAINT GREEN (-5120 1030);
DISPLAY INVISIBLE (-5120 1030);
FORCEPROP 2 LAST PATH I156
J 0
(-4900 1200);
DISPLAY 1.021277 (-4900 1200);
PAINT ORANGE (-4900 1200);
DISPLAY INVISIBLE (-4900 1200);
FORCEADD OFFPAGE..2
(-5150 1575);
FORCEPROP 2 LAST $XR0 223 
J 0
(-4961 1575);
DISPLAY 0.638298 (-4961 1575);
PAINT MONO (-4961 1575);
FORCEPROP 2 LAST $XR1 226 
J 0
(-4841 1575);
DISPLAY 0.638298 (-4841 1575);
PAINT MONO (-4841 1575);
FORCEPROP 2 LAST $XR2 55 
J 0
(-4721 1575);
DISPLAY 0.638298 (-4721 1575);
PAINT MONO (-4721 1575);
FORCEPROP 2 LAST CDS_LIB mstr_standard
J 0
(-5150 1575);
PAINT ORANGE (-5150 1575);
DISPLAY INVISIBLE (-5150 1575);
FORCEPROP 2 LAST ROOM P0V95_FPGA_CPU0_VR
J 0
(-5575 1650);
DISPLAY 1.361702 (-5575 1650);
PAINT ORANGE (-5575 1650);
DISPLAY INVISIBLE (-5575 1650);
FORCEPROP 1 LAST OFFPAGE TRUE
J 0
(-4825 1450);
DISPLAY 1.170213 (-4825 1450);
PAINT GREEN (-4825 1450);
DISPLAY INVISIBLE (-4825 1450);
FORCEPROP 1 LAST COMMENT_BODY TRUE
J 0
(-5195 1480);
DISPLAY 1.170213 (-5195 1480);
PAINT GREEN (-5195 1480);
DISPLAY INVISIBLE (-5195 1480);
FORCEPROP 2 LAST PATH I157
J 0
(-4700 1625);
DISPLAY 1.021277 (-4700 1625);
PAINT ORANGE (-4700 1625);
DISPLAY INVISIBLE (-4700 1625);
FORCEADD VCC_CORE..1
(-2300 4600);
FORCEPROP 3 LASTPIN (-2300 4550) SIG_NAME PVCCMCP_CPU1\g
J 0
(-2290 4560);
DISPLAY 0.659574 (-2290 4560);
PAINT MONO (-2290 4560);
DISPLAY INVISIBLE (-2290 4560);
FORCEPROP 1 LAST HDL_POWER PVCCMCP_CPU1
J 1
(-2300 4650);
DISPLAY 0.617021 (-2300 4650);
PAINT GREEN (-2300 4650);
FORCEPROP 0 LAST VOLTAGE +0.95
J 0
(-2300 4750);
DISPLAY 1.021277 (-2300 4750);
PAINT SKYBLUE (-2300 4750);
DISPLAY INVISIBLE (-2300 4750);
FORCEPROP 2 LAST CDS_LIB mstr_symbols
J 0
(-2300 4600);
PAINT ORANGE (-2300 4600);
DISPLAY INVISIBLE (-2300 4600);
FORCEPROP 1 LAST PATH I161
J 0
(-2250 4625);
DISPLAY 0.872340 (-2250 4625);
PAINT AQUA (-2250 4625);
DISPLAY INVISIBLE (-2250 4625);
FORCEADD VCC_CORE..1
(-5075 3700);
FORCEPROP 3 LASTPIN (-5075 3650) SIG_NAME PVCCMCP_CPU1\g
J 0
(-5065 3660);
DISPLAY 0.659574 (-5065 3660);
PAINT MONO (-5065 3660);
DISPLAY INVISIBLE (-5065 3660);
FORCEPROP 1 LAST HDL_POWER PVCCMCP_CPU1
J 1
(-5075 3750);
DISPLAY 0.617021 (-5075 3750);
PAINT GREEN (-5075 3750);
FORCEPROP 2 LAST CDS_LIB mstr_symbols
J 0
(-5075 3700);
PAINT ORANGE (-5075 3700);
DISPLAY INVISIBLE (-5075 3700);
FORCEPROP 1 LAST PATH I162
J 0
(-5025 3725);
DISPLAY 0.872340 (-5025 3725);
PAINT AQUA (-5025 3725);
DISPLAY INVISIBLE (-5025 3725);
FORCEADD VCC_CORE..1
(-1700 2125);
FORCEPROP 3 LASTPIN (-1700 2075) SIG_NAME P1V8_MCP_CPU1\g
J 0
(-1690 2085);
DISPLAY 0.659574 (-1690 2085);
PAINT MONO (-1690 2085);
DISPLAY INVISIBLE (-1690 2085);
FORCEPROP 1 LAST HDL_POWER P1V8_MCP_CPU1
J 1
(-1700 2175);
DISPLAY 0.617021 (-1700 2175);
PAINT GREEN (-1700 2175);
FORCEPROP 0 LAST VOLTAGE 1.8
J 0
(-1700 2275);
DISPLAY 1.021277 (-1700 2275);
PAINT SKYBLUE (-1700 2275);
DISPLAY INVISIBLE (-1700 2275);
FORCEPROP 2 LAST CDS_LIB mstr_symbols
J 0
(-1700 2125);
PAINT ORANGE (-1700 2125);
DISPLAY INVISIBLE (-1700 2125);
FORCEPROP 1 LAST PATH I164
J 0
(-1650 2150);
DISPLAY 0.872340 (-1650 2150);
PAINT AQUA (-1650 2150);
DISPLAY INVISIBLE (-1650 2150);
FORCEADD VCC_CORE..1
(-1225 2250);
FORCEPROP 3 LASTPIN (-1225 2200) SIG_NAME P1V8_MCP_CPU1\g
J 0
(-1215 2210);
DISPLAY 0.659574 (-1215 2210);
PAINT MONO (-1215 2210);
DISPLAY INVISIBLE (-1215 2210);
FORCEPROP 1 LAST HDL_POWER P1V8_MCP_CPU1
J 1
(-1225 2300);
DISPLAY 0.617021 (-1225 2300);
PAINT GREEN (-1225 2300);
FORCEPROP 0 LAST VOLTAGE 1.8
J 0
(-1225 2400);
DISPLAY 1.021277 (-1225 2400);
PAINT SKYBLUE (-1225 2400);
DISPLAY INVISIBLE (-1225 2400);
FORCEPROP 2 LAST CDS_LIB mstr_symbols
J 0
(-1225 2250);
PAINT ORANGE (-1225 2250);
DISPLAY INVISIBLE (-1225 2250);
FORCEPROP 1 LAST PATH I165
J 0
(-1175 2275);
DISPLAY 0.872340 (-1175 2275);
PAINT AQUA (-1175 2275);
DISPLAY INVISIBLE (-1175 2275);
FORCEADD VCC_CORE..1
(-1150 4600);
FORCEPROP 3 LASTPIN (-1150 4550) SIG_NAME PVCCIOMCP_CPU1\g
J 0
(-1140 4560);
DISPLAY 0.659574 (-1140 4560);
PAINT MONO (-1140 4560);
DISPLAY INVISIBLE (-1140 4560);
FORCEPROP 1 LAST HDL_POWER PVCCIOMCP_CPU1
J 1
(-1150 4650);
DISPLAY 0.617021 (-1150 4650);
PAINT GREEN (-1150 4650);
FORCEPROP 0 LAST VOLTAGE +0.95
J 0
(-1150 4750);
DISPLAY 1.021277 (-1150 4750);
PAINT SKYBLUE (-1150 4750);
DISPLAY INVISIBLE (-1150 4750);
FORCEPROP 2 LAST CDS_LIB mstr_symbols
J 0
(-1150 4600);
PAINT ORANGE (-1150 4600);
DISPLAY INVISIBLE (-1150 4600);
FORCEPROP 1 LAST PATH I166
J 0
(-1100 4625);
DISPLAY 0.872340 (-1100 4625);
PAINT AQUA (-1100 4625);
DISPLAY INVISIBLE (-1100 4625);
FORCEADD VCC_CORE..1
(-1775 4600);
FORCEPROP 3 LASTPIN (-1775 4550) SIG_NAME PVCCIOMCP_CPU1\g
J 0
(-1765 4560);
DISPLAY 0.659574 (-1765 4560);
PAINT MONO (-1765 4560);
DISPLAY INVISIBLE (-1765 4560);
FORCEPROP 1 LAST HDL_POWER PVCCIOMCP_CPU1
J 1
(-1775 4650);
DISPLAY 0.617021 (-1775 4650);
PAINT GREEN (-1775 4650);
FORCEPROP 0 LAST VOLTAGE +0.95
J 0
(-1775 4750);
DISPLAY 1.021277 (-1775 4750);
PAINT SKYBLUE (-1775 4750);
DISPLAY INVISIBLE (-1775 4750);
FORCEPROP 2 LAST CDS_LIB mstr_symbols
J 0
(-1775 4600);
PAINT ORANGE (-1775 4600);
DISPLAY INVISIBLE (-1775 4600);
FORCEPROP 1 LAST PATH I167
J 0
(-1725 4625);
DISPLAY 0.872340 (-1725 4625);
PAINT AQUA (-1725 4625);
DISPLAY INVISIBLE (-1725 4625);
FORCEADD VCC_CORE..1
(-1550 3275);
FORCEPROP 3 LASTPIN (-1550 3225) SIG_NAME PVCCMCP_CPU1\g
J 0
(-1540 3235);
DISPLAY 0.659574 (-1540 3235);
PAINT MONO (-1540 3235);
DISPLAY INVISIBLE (-1540 3235);
FORCEPROP 1 LAST HDL_POWER PVCCMCP_CPU1
J 1
(-1550 3325);
DISPLAY 0.617021 (-1550 3325);
PAINT GREEN (-1550 3325);
FORCEPROP 0 LAST VOLTAGE +0.95
J 0
(-1550 3425);
DISPLAY 1.021277 (-1550 3425);
PAINT SKYBLUE (-1550 3425);
DISPLAY INVISIBLE (-1550 3425);
FORCEPROP 2 LAST CDS_LIB mstr_symbols
J 0
(-1550 3275);
PAINT ORANGE (-1550 3275);
DISPLAY INVISIBLE (-1550 3275);
FORCEPROP 1 LAST PATH I168
J 0
(-1500 3300);
DISPLAY 0.872340 (-1500 3300);
PAINT AQUA (-1500 3300);
DISPLAY INVISIBLE (-1500 3300);
FORCEADD RES..2
(-7950 775);
FORCEPROP 1 LAST LOCATION R4C12
J 0
(-7905 900);
DISPLAY 0.617021 (-7905 900);
PAINT AQUA (-7905 900);
FORCEPROP 1 LAST PART_NUMBER G21796-078
J 0
(-7910 650);
DISPLAY 0.617021 (-7910 650);
PAINT BLUE (-7910 650);
FORCEPROP 1 LAST VALUE 8.06K
J 0
(-7905 850);
DISPLAY 0.617021 (-7905 850);
PAINT SKYBLUE (-7905 850);
FORCEPROP 1 LAST TOLERANCE 1%
J 0
(-7905 800);
DISPLAY 0.617021 (-7905 800);
PAINT SKYBLUE (-7905 800);
FORCEPROP 1 LAST PACK_TYPE 0402
J 0
(-7910 600);
DISPLAY 0.617021 (-7910 600);
PAINT SKYBLUE (-7910 600);
FORCEPROP 1 LAST MATERIAL CHIP
J 0
(-7910 700);
DISPLAY 0.617021 (-7910 700);
PAINT SKYBLUE (-7910 700);
FORCEPROP 1 LAST WATTAGE 1/16W
J 0
(-7910 750);
DISPLAY 0.617021 (-7910 750);
PAINT SKYBLUE (-7910 750);
FORCEPROP 1 LASTPIN (-7950 675) $PN 2
J 0
(-7945 685);
DISPLAY 0.617021 (-7945 685);
PAINT ORANGE (-7945 685);
FORCEPROP 1 LASTPIN (-7950 875) $PN 1
J 0
(-7945 837);
DISPLAY 0.617021 (-7945 837);
PAINT ORANGE (-7945 837);
FORCEPROP 2 LAST SEC_TYPE 0402
J 0
(-7900 1000);
DISPLAY 1.021277 (-7900 1000);
PAINT ORANGE (-7900 1000);
DISPLAY INVISIBLE (-7900 1000);
FORCEPROP 2 LAST CDS_LIB mstr_discrete
J 0
(-7950 775);
PAINT ORANGE (-7950 775);
DISPLAY INVISIBLE (-7950 775);
FORCEPROP 2 LAST SEC 1
J 0
(-7900 1000);
PAINT MONO (-7900 1000);
DISPLAY INVISIBLE (-7900 1000);
FORCEPROP 1 LAST PATH I169
J 0
(-7900 950);
DISPLAY 0.978723 (-7900 950);
PAINT WHITE (-7900 950);
DISPLAY INVISIBLE (-7900 950);
FORCEPROP 0 LAST ROOM PVCCIN_CPU0_VR
J 0
(-7900 1000);
DISPLAY 1.021277 (-7900 1000);
PAINT ORANGE (-7900 1000);
DISPLAY INVISIBLE (-7900 1000);
FORCEADD RES..2
(-7600 750);
FORCEPROP 1 LAST LOCATION R4C11
J 0
(-7555 875);
DISPLAY 0.617021 (-7555 875);
PAINT AQUA (-7555 875);
FORCEPROP 1 LAST PART_NUMBER G21796-043
J 0
(-7560 625);
DISPLAY 0.617021 (-7560 625);
PAINT BLUE (-7560 625);
FORCEPROP 1 LAST VALUE 3.16K
J 0
(-7555 825);
DISPLAY 0.617021 (-7555 825);
PAINT SKYBLUE (-7555 825);
FORCEPROP 1 LAST TOLERANCE 1%
J 0
(-7555 775);
DISPLAY 0.617021 (-7555 775);
PAINT SKYBLUE (-7555 775);
FORCEPROP 1 LAST PACK_TYPE 0402
J 0
(-7560 575);
DISPLAY 0.617021 (-7560 575);
PAINT SKYBLUE (-7560 575);
FORCEPROP 1 LAST MATERIAL CHIP
J 0
(-7560 675);
DISPLAY 0.617021 (-7560 675);
PAINT SKYBLUE (-7560 675);
FORCEPROP 1 LAST WATTAGE 1/16W
J 0
(-7560 725);
DISPLAY 0.617021 (-7560 725);
PAINT SKYBLUE (-7560 725);
FORCEPROP 1 LASTPIN (-7600 650) $PN 2
J 0
(-7595 660);
DISPLAY 0.617021 (-7595 660);
PAINT ORANGE (-7595 660);
FORCEPROP 1 LASTPIN (-7600 850) $PN 1
J 0
(-7595 812);
DISPLAY 0.617021 (-7595 812);
PAINT ORANGE (-7595 812);
FORCEPROP 2 LAST SEC_TYPE 0402
J 0
(-7550 975);
DISPLAY 1.021277 (-7550 975);
PAINT ORANGE (-7550 975);
DISPLAY INVISIBLE (-7550 975);
FORCEPROP 2 LAST CDS_LIB mstr_discrete
J 0
(-7600 750);
PAINT ORANGE (-7600 750);
DISPLAY INVISIBLE (-7600 750);
FORCEPROP 2 LAST SEC 1
J 0
(-7550 975);
PAINT MONO (-7550 975);
DISPLAY INVISIBLE (-7550 975);
FORCEPROP 1 LAST PATH I170
J 0
(-7550 925);
DISPLAY 0.978723 (-7550 925);
PAINT WHITE (-7550 925);
DISPLAY INVISIBLE (-7550 925);
FORCEPROP 0 LAST ROOM PVCCIN_CPU0_VR
J 0
(-7550 975);
DISPLAY 1.021277 (-7550 975);
PAINT ORANGE (-7550 975);
DISPLAY INVISIBLE (-7550 975);
FORCEADD GND..1
(-7750 425);
FORCEPROP 3 LASTPIN (-7750 475) SIG_NAME GND\g
J 0
(-7740 485);
DISPLAY 0.659574 (-7740 485);
PAINT MONO (-7740 485);
DISPLAY INVISIBLE (-7740 485);
FORCEPROP 1 LAST VOLTAGE 0.0V
J 0
(-7795 382);
DISPLAY 0.340426 (-7795 382);
PAINT SKYBLUE (-7795 382);
DISPLAY INVISIBLE (-7795 382);
FORCEPROP 2 LAST CDS_LIB mstr_symbols
J 0
(-7750 425);
PAINT ORANGE (-7750 425);
DISPLAY INVISIBLE (-7750 425);
FORCEPROP 1 LAST SIZE 1B
J 0
(-7675 375);
DISPLAY 1.404255 (-7675 375);
PAINT AQUA (-7675 375);
DISPLAY INVISIBLE (-7675 375);
FORCEPROP 1 LAST BODY_TYPE PLUMBING
J 0
(-7795 382);
DISPLAY 0.340426 (-7795 382);
PAINT GREEN (-7795 382);
DISPLAY INVISIBLE (-7795 382);
FORCEPROP 1 LAST PATH I171
J 0
(-7675 425);
DISPLAY 0.872340 (-7675 425);
PAINT AQUA (-7675 425);
DISPLAY INVISIBLE (-7675 425);
FORCEPROP 1 LAST HDL_POWER GND
J 0
(-7750 575);
PAINT GREEN (-7750 575);
DISPLAY INVISIBLE (-7750 575);
FORCEADD P3V3..1
(-7325 4500);
FORCEPROP 3 LASTPIN (-7325 4450) SIG_NAME P3V3\g
J 0
(-7315 4460);
DISPLAY 0.659574 (-7315 4460);
PAINT MONO (-7315 4460);
DISPLAY INVISIBLE (-7315 4460);
FORCEPROP 1 LAST VOLTAGE +3.3V
J 0
(-7225 4650);
DISPLAY 1.021277 (-7225 4650);
PAINT SKYBLUE (-7225 4650);
DISPLAY INVISIBLE (-7225 4650);
FORCEPROP 1 LAST SIZE 1B
J 0
(-7280 4522);
DISPLAY 0.340426 (-7280 4522);
PAINT GREEN (-7280 4522);
DISPLAY INVISIBLE (-7280 4522);
FORCEPROP 2 LAST CDS_LIB mstr_symbols
J 0
(-7325 4500);
PAINT ORANGE (-7325 4500);
DISPLAY INVISIBLE (-7325 4500);
FORCEPROP 1 LAST BODY_TYPE PLUMBING
J 0
(-7370 4457);
DISPLAY 0.340426 (-7370 4457);
PAINT GREEN (-7370 4457);
DISPLAY INVISIBLE (-7370 4457);
FORCEPROP 1 LAST PATH I173
J 0
(-7280 4502);
DISPLAY 0.340426 (-7280 4502);
PAINT GREEN (-7280 4502);
DISPLAY INVISIBLE (-7280 4502);
FORCEPROP 1 LAST HDL_POWER P3V3
J 0
(-7650 4375);
DISPLAY 0.872340 (-7650 4375);
PAINT ORANGE (-7650 4375);
DISPLAY INVISIBLE (-7650 4375);
FORCEADD OFFPAGE..1
(-7975 4225);
FORCEPROP 2 LAST $XR0 104 
J 0
(-8227 4225);
DISPLAY 0.638298 (-8227 4225);
PAINT MONO (-8227 4225);
FORCEPROP 2 LAST CDS_LIB mstr_standard
J 0
(-7975 4225);
PAINT ORANGE (-7975 4225);
DISPLAY INVISIBLE (-7975 4225);
FORCEPROP 1 LAST OFFPAGE TRUE
J 0
(-7650 4100);
DISPLAY 0.872340 (-7650 4100);
PAINT GREEN (-7650 4100);
DISPLAY INVISIBLE (-7650 4100);
FORCEPROP 1 LAST COMMENT_BODY TRUE
J 0
(-7850 4125);
DISPLAY 0.872340 (-7850 4125);
PAINT GREEN (-7850 4125);
DISPLAY INVISIBLE (-7850 4125);
FORCEPROP 2 LAST PATH I174
J 0
(-7925 4300);
DISPLAY 1.021277 (-7925 4300);
PAINT ORANGE (-7925 4300);
DISPLAY INVISIBLE (-7925 4300);
FORCEADD OFFPAGE..3
(-5100 1225);
FORCEPROP 2 LAST $XR0 55 
J 0
(-4886 1225);
DISPLAY 0.638298 (-4886 1225);
PAINT MONO (-4886 1225);
FORCEPROP 2 LAST $XR1 206 
J 0
(-4796 1225);
DISPLAY 0.638298 (-4796 1225);
PAINT MONO (-4796 1225);
FORCEPROP 2 LAST $XR2 213 
J 0
(-4676 1225);
DISPLAY 0.638298 (-4676 1225);
PAINT MONO (-4676 1225);
FORCEPROP 2 LAST CDS_LIB mstr_standard
J 0
(-5100 1225);
PAINT ORANGE (-5100 1225);
DISPLAY INVISIBLE (-5100 1225);
FORCEPROP 2 LAST ROOM P0V95_FPGA_CPU0_VR
J 0
(-5500 1300);
DISPLAY 1.361702 (-5500 1300);
PAINT ORANGE (-5500 1300);
DISPLAY INVISIBLE (-5500 1300);
FORCEPROP 1 LAST OFFPAGE TRUE
J 0
(-4775 1100);
DISPLAY 1.170213 (-4775 1100);
PAINT GREEN (-4775 1100);
DISPLAY INVISIBLE (-4775 1100);
FORCEPROP 1 LAST COMMENT_BODY TRUE
J 0
(-5150 1125);
DISPLAY 1.170213 (-5150 1125);
PAINT GREEN (-5150 1125);
DISPLAY INVISIBLE (-5150 1125);
FORCEPROP 2 LAST PATH I2
J 0
(-4900 1300);
DISPLAY 1.021277 (-4900 1300);
PAINT ORANGE (-4900 1300);
DISPLAY INVISIBLE (-4900 1300);
FORCEADD CAPP..1
(-1775 4275);
FORCEPROP 1 LAST LOCATION C4C1
J 0
(-1725 4375);
DISPLAY 0.617021 (-1725 4375);
PAINT AQUA (-1725 4375);
FORCEPROP 1 LAST PART_NUMBER 699013-049
J 0
(-1725 4075);
DISPLAY 0.617021 (-1725 4075);
PAINT BLUE (-1725 4075);
FORCEPROP 1 LAST VALUE 470UF
J 0
(-1725 4325);
DISPLAY 0.617021 (-1725 4325);
PAINT SKYBLUE (-1725 4325);
FORCEPROP 1 LAST TOLERANCE 20%
J 0
(-1725 4275);
DISPLAY 0.617021 (-1725 4275);
PAINT SKYBLUE (-1725 4275);
FORCEPROP 1 LAST PACK_TYPE 3018
J 0
(-1725 4125);
DISPLAY 0.617021 (-1725 4125);
PAINT SKYBLUE (-1725 4125);
FORCEPROP 1 LAST VOLTAGE 2.5V
J 0
(-1725 4225);
DISPLAY 0.617021 (-1725 4225);
PAINT SKYBLUE (-1725 4225);
FORCEPROP 1 LAST MATERIAL ALUM
J 0
(-1725 4175);
DISPLAY 0.617021 (-1725 4175);
PAINT SKYBLUE (-1725 4175);
FORCEPROP 1 LASTPIN (-1775 4175) $PN 2
J 0
(-1765 4160);
DISPLAY 0.617021 (-1765 4160);
PAINT ORANGE (-1765 4160);
FORCEPROP 1 LASTPIN (-1775 4375) $PN 1
J 0
(-1765 4360);
DISPLAY 0.617021 (-1765 4360);
PAINT ORANGE (-1765 4360);
FORCEPROP 2 LAST CDS_LIB mstr_discrete
J 0
(-1775 4275);
PAINT ORANGE (-1775 4275);
DISPLAY INVISIBLE (-1775 4275);
FORCEPROP 2 LAST SEC_TYPE 3018
J 0
(-1725 4475);
DISPLAY 1.021277 (-1725 4475);
PAINT ORANGE (-1725 4475);
DISPLAY INVISIBLE (-1725 4475);
FORCEPROP 2 LAST BOM_COST PROC_VRD_VCCIN_CPU1
J 0
(-1725 4425);
PAINT MONO (-1725 4425);
DISPLAY INVISIBLE (-1725 4425);
FORCEPROP 2 LAST SEC 1
J 0
(-1725 4475);
PAINT MONO (-1725 4475);
DISPLAY INVISIBLE (-1725 4475);
FORCEPROP 2 LAST CDS_LOCATION C4C1
J 0
(-1725 4375);
DISPLAY 0.617021 (-1725 4375);
PAINT AQUA (-1725 4375);
DISPLAY INVISIBLE (-1725 4375);
FORCEPROP 1 LAST PATH I29
J 0
(-1725 4425);
DISPLAY 0.978723 (-1725 4425);
PAINT ORANGE (-1725 4425);
DISPLAY INVISIBLE (-1725 4425);
FORCEPROP 2 LAST ROOM P0V95_MCP_CPU1_DECAP_VR
J 0
(-1725 4400);
PAINT MONO (-1725 4400);
DISPLAY INVISIBLE (-1725 4400);
FORCEADD GND..1
(-1775 3875);
FORCEPROP 3 LASTPIN (-1775 3925) SIG_NAME GND\g
J 0
(-1765 3935);
DISPLAY 0.659574 (-1765 3935);
PAINT MONO (-1765 3935);
DISPLAY INVISIBLE (-1765 3935);
FORCEPROP 1 LAST VOLTAGE 0
J 0
(-1775 3875);
PAINT SKYBLUE (-1775 3875);
DISPLAY INVISIBLE (-1775 3875);
FORCEPROP 1 LAST SIZE 1B
J 0
(-1700 3825);
DISPLAY 1.723404 (-1700 3825);
PAINT GREEN (-1700 3825);
DISPLAY INVISIBLE (-1700 3825);
FORCEPROP 2 LAST CDS_LIB mstr_symbols
J 0
(-1775 3875);
PAINT ORANGE (-1775 3875);
DISPLAY INVISIBLE (-1775 3875);
FORCEPROP 2 LAST BOM_COST PROC_VRD_VCCIN_CPU0
J 0
(-2150 3950);
DISPLAY 1.446809 (-2150 3950);
PAINT MONO (-2150 3950);
DISPLAY INVISIBLE (-2150 3950);
FORCEPROP 1 LAST BODY_TYPE PLUMBING
J 0
(-1820 3832);
DISPLAY 0.340426 (-1820 3832);
PAINT GREEN (-1820 3832);
DISPLAY INVISIBLE (-1820 3832);
FORCEPROP 1 LAST PATH I30
J 0
(-1700 3875);
DISPLAY 0.872340 (-1700 3875);
PAINT AQUA (-1700 3875);
DISPLAY INVISIBLE (-1700 3875);
FORCEPROP 2 LAST ROOM PVSA_CPU0_DECAP_VR
J 0
(-2325 3950);
DISPLAY 1.936170 (-2325 3950);
PAINT ORANGE (-2325 3950);
DISPLAY INVISIBLE (-2325 3950);
FORCEPROP 1 LAST HDL_POWER GND
J 0
(-1775 4025);
DISPLAY 1.723404 (-1775 4025);
PAINT GREEN (-1775 4025);
DISPLAY INVISIBLE (-1775 4025);
FORCEADD CAP_A..1
R 2
(-700 4225);
FORCEPROP 1 LAST LOCATION C3C2
J 2
(-750 4325);
DISPLAY 0.617021 (-750 4325);
PAINT AQUA (-750 4325);
FORCEPROP 1 LAST PART_NUMBER D97712-004
J 2
(-750 4075);
DISPLAY 0.617021 (-750 4075);
PAINT BLUE (-750 4075);
FORCEPROP 1 LAST VALUE 1.0UF
J 2
(-750 4275);
DISPLAY 0.617021 (-750 4275);
PAINT SKYBLUE (-750 4275);
FORCEPROP 1 LAST TOLERANCE 10%
J 2
(-750 4175);
DISPLAY 0.617021 (-750 4175);
PAINT SKYBLUE (-750 4175);
FORCEPROP 1 LAST PACK_TYPE 0402V
J 2
(-750 4025);
DISPLAY 0.617021 (-750 4025);
PAINT SKYBLUE (-750 4025);
FORCEPROP 1 LAST VOLTAGE 6.3V
J 2
(-750 4225);
DISPLAY 0.617021 (-750 4225);
PAINT SKYBLUE (-750 4225);
FORCEPROP 1 LAST MATERIAL X6S
J 2
(-750 4125);
DISPLAY 0.617021 (-750 4125);
PAINT SKYBLUE (-750 4125);
FORCEPROP 1 LASTPIN (-700 4325) $PN 1
J 2
(-710 4305);
DISPLAY 0.617021 (-710 4305);
PAINT ORANGE (-710 4305);
FORCEPROP 1 LASTPIN (-700 4125) $PN 2
J 2
(-710 4105);
DISPLAY 0.617021 (-710 4105);
PAINT ORANGE (-710 4105);
FORCEPROP 2 LAST CDS_LOCATION C3C2
J 2
(-750 4325);
DISPLAY 0.617021 (-750 4325);
PAINT AQUA (-750 4325);
DISPLAY INVISIBLE (-750 4325);
FORCEPROP 2 LAST CDS_LIB dev_discrete
J 0
(-700 4225);
PAINT ORANGE (-700 4225);
DISPLAY INVISIBLE (-700 4225);
FORCEPROP 2 LAST CDS_SEC 1
J 0
(-750 4375);
PAINT ORANGE (-750 4375);
DISPLAY INVISIBLE (-750 4375);
FORCEPROP 2 LAST SEC_TYPE 0402V
J 0
(-750 4425);
DISPLAY 1.021277 (-750 4425);
PAINT ORANGE (-750 4425);
DISPLAY INVISIBLE (-750 4425);
FORCEPROP 2 LAST SEC 1
J 0
(-750 4425);
DISPLAY 0.680851 (-750 4425);
PAINT MONO (-750 4425);
DISPLAY INVISIBLE (-750 4425);
FORCEPROP 1 LAST PATH I31
J 2
(-750 4375);
DISPLAY 0.978723 (-750 4375);
PAINT WHITE (-750 4375);
DISPLAY INVISIBLE (-750 4375);
FORCEPROP 2 LAST ROOM P0V95_FPGA_CPU1
J 2
(-750 4375);
DISPLAY 1.659574 (-750 4375);
PAINT WHITE (-750 4375);
DISPLAY INVISIBLE (-750 4375);
FORCEADD GND..1
(-1150 3850);
FORCEPROP 3 LASTPIN (-1150 3900) SIG_NAME GND\g
J 0
(-1140 3910);
DISPLAY 0.659574 (-1140 3910);
PAINT MONO (-1140 3910);
DISPLAY INVISIBLE (-1140 3910);
FORCEPROP 1 LAST VOLTAGE 0.0V
J 0
(-1195 3807);
DISPLAY 0.340426 (-1195 3807);
PAINT SKYBLUE (-1195 3807);
DISPLAY INVISIBLE (-1195 3807);
FORCEPROP 2 LAST CDS_LIB mstr_symbols
J 0
(-1150 3850);
PAINT ORANGE (-1150 3850);
DISPLAY INVISIBLE (-1150 3850);
FORCEPROP 1 LAST SIZE 1B
J 0
(-1075 3800);
DISPLAY 1.404255 (-1075 3800);
PAINT AQUA (-1075 3800);
DISPLAY INVISIBLE (-1075 3800);
FORCEPROP 1 LAST BODY_TYPE PLUMBING
J 0
(-1195 3807);
DISPLAY 0.340426 (-1195 3807);
PAINT GREEN (-1195 3807);
DISPLAY INVISIBLE (-1195 3807);
FORCEPROP 1 LAST PATH I37
J 0
(-1075 3850);
DISPLAY 0.872340 (-1075 3850);
PAINT AQUA (-1075 3850);
DISPLAY INVISIBLE (-1075 3850);
FORCEPROP 1 LAST HDL_POWER GND
J 0
(-1150 4000);
PAINT GREEN (-1150 4000);
DISPLAY INVISIBLE (-1150 4000);
FORCEADD CAP_A..1
R 2
(-1150 4200);
FORCEPROP 1 LAST LOCATION C3C1
J 2
(-1200 4300);
DISPLAY 0.617021 (-1200 4300);
PAINT AQUA (-1200 4300);
FORCEPROP 1 LAST PART_NUMBER D97712-004
J 2
(-1200 4050);
DISPLAY 0.617021 (-1200 4050);
PAINT BLUE (-1200 4050);
FORCEPROP 1 LAST VALUE 1.0UF
J 2
(-1200 4250);
DISPLAY 0.617021 (-1200 4250);
PAINT SKYBLUE (-1200 4250);
FORCEPROP 1 LAST TOLERANCE 10%
J 2
(-1200 4150);
DISPLAY 0.617021 (-1200 4150);
PAINT SKYBLUE (-1200 4150);
FORCEPROP 1 LAST PACK_TYPE 0402V
J 2
(-1200 4000);
DISPLAY 0.617021 (-1200 4000);
PAINT SKYBLUE (-1200 4000);
FORCEPROP 1 LAST VOLTAGE 6.3V
J 2
(-1200 4200);
DISPLAY 0.617021 (-1200 4200);
PAINT SKYBLUE (-1200 4200);
FORCEPROP 1 LAST MATERIAL X6S
J 2
(-1200 4100);
DISPLAY 0.617021 (-1200 4100);
PAINT SKYBLUE (-1200 4100);
FORCEPROP 1 LASTPIN (-1150 4300) $PN 1
J 2
(-1160 4280);
DISPLAY 0.617021 (-1160 4280);
PAINT ORANGE (-1160 4280);
FORCEPROP 1 LASTPIN (-1150 4100) $PN 2
J 2
(-1160 4080);
DISPLAY 0.617021 (-1160 4080);
PAINT ORANGE (-1160 4080);
FORCEPROP 2 LAST CDS_LOCATION C3C1
J 2
(-1200 4300);
DISPLAY 0.617021 (-1200 4300);
PAINT AQUA (-1200 4300);
DISPLAY INVISIBLE (-1200 4300);
FORCEPROP 2 LAST CDS_LIB dev_discrete
J 0
(-1150 4200);
PAINT ORANGE (-1150 4200);
DISPLAY INVISIBLE (-1150 4200);
FORCEPROP 2 LAST CDS_SEC 1
J 0
(-1200 4350);
PAINT ORANGE (-1200 4350);
DISPLAY INVISIBLE (-1200 4350);
FORCEPROP 2 LAST SEC_TYPE 0402V
J 0
(-1200 4400);
DISPLAY 1.021277 (-1200 4400);
PAINT ORANGE (-1200 4400);
DISPLAY INVISIBLE (-1200 4400);
FORCEPROP 2 LAST SEC 1
J 0
(-1200 4400);
DISPLAY 0.680851 (-1200 4400);
PAINT MONO (-1200 4400);
DISPLAY INVISIBLE (-1200 4400);
FORCEPROP 1 LAST PATH I38
J 2
(-1200 4350);
DISPLAY 0.978723 (-1200 4350);
PAINT WHITE (-1200 4350);
DISPLAY INVISIBLE (-1200 4350);
FORCEPROP 2 LAST ROOM P0V95_FPGA_CPU1
J 2
(-1200 4350);
DISPLAY 1.659574 (-1200 4350);
PAINT WHITE (-1200 4350);
DISPLAY INVISIBLE (-1200 4350);
FORCEADD OFFPAGE..3
(-5150 1925);
FORCEPROP 2 LAST $XR0 138 
J 0
(-4936 1925);
DISPLAY 0.638298 (-4936 1925);
PAINT MONO (-4936 1925);
FORCEPROP 2 LAST $XR1 159 
J 0
(-4816 1925);
DISPLAY 0.638298 (-4816 1925);
PAINT MONO (-4816 1925);
FORCEPROP 2 LAST $XR2 194 
J 0
(-4696 1925);
DISPLAY 0.638298 (-4696 1925);
PAINT MONO (-4696 1925);
FORCEPROP 2 LAST $XR3 201 
J 0
(-4576 1925);
DISPLAY 0.638298 (-4576 1925);
PAINT MONO (-4576 1925);
FORCEPROP 2 LAST $XR4 206 
J 0
(-4456 1925);
DISPLAY 0.638298 (-4456 1925);
PAINT MONO (-4456 1925);
FORCEPROP 2 LAST $XR5 211 
J 0
(-4336 1925);
DISPLAY 0.638298 (-4336 1925);
PAINT MONO (-4336 1925);
FORCEPROP 2 LAST $XR6 213 
J 0
(-4216 1925);
DISPLAY 0.638298 (-4216 1925);
PAINT MONO (-4216 1925);
FORCEPROP 2 LAST $XR7 215 
J 0
(-4096 1925);
DISPLAY 0.638298 (-4096 1925);
PAINT MONO (-4096 1925);
FORCEPROP 2 LAST $XR8 218 
J 0
(-4936 1889);
DISPLAY 0.638298 (-4936 1889);
PAINT MONO (-4936 1889);
FORCEPROP 2 LAST $XR9 223 
J 0
(-4816 1889);
DISPLAY 0.638298 (-4816 1889);
PAINT MONO (-4816 1889);
FORCEPROP 2 LAST $XR10 226 
J 0
(-4696 1889);
DISPLAY 0.638298 (-4696 1889);
PAINT MONO (-4696 1889);
FORCEPROP 2 LAST $XR11 235 
J 0
(-4576 1889);
DISPLAY 0.638298 (-4576 1889);
PAINT MONO (-4576 1889);
FORCEPROP 2 LAST ROOM P0V95_FPGA_CPU0_VR
J 0
(-5550 2000);
DISPLAY 1.361702 (-5550 2000);
PAINT ORANGE (-5550 2000);
DISPLAY INVISIBLE (-5550 2000);
FORCEPROP 2 LAST CDS_LIB mstr_standard
J 0
(-5150 1925);
PAINT ORANGE (-5150 1925);
DISPLAY INVISIBLE (-5150 1925);
FORCEPROP 1 LAST OFFPAGE TRUE
J 0
(-4825 1800);
DISPLAY 1.170213 (-4825 1800);
PAINT GREEN (-4825 1800);
DISPLAY INVISIBLE (-4825 1800);
FORCEPROP 1 LAST COMMENT_BODY TRUE
J 0
(-5200 1825);
DISPLAY 1.170213 (-5200 1825);
PAINT GREEN (-5200 1825);
DISPLAY INVISIBLE (-5200 1825);
FORCEPROP 2 LAST PATH I4
J 0
(-4325 1975);
DISPLAY 1.021277 (-4325 1975);
PAINT ORANGE (-4325 1975);
DISPLAY INVISIBLE (-4325 1975);
FORCEADD SCONN120_H61426002..1
(-3150 2800);
FORCEPROP 1 LAST LOCATION J4E1
J 0
(-3500 4800);
DISPLAY 0.617021 (-3500 4800);
PAINT AQUA (-3500 4800);
FORCEPROP 1 LAST PART_NUMBER H61426-002
J 0
(-3500 900);
DISPLAY 0.617021 (-3500 900);
PAINT BLUE (-3500 900);
FORCEPROP 1 LAST MATERIAL CONN
J 0
(-3500 4750);
DISPLAY 0.617021 (-3500 4750);
PAINT SKYBLUE (-3500 4750);
FORCEPROP 2 LASTPIN (-2750 1100) $PN F20
J 0
(-2740 1110);
DISPLAY 0.617021 (-2740 1110);
PAINT ORANGE (-2740 1110);
FORCEPROP 2 LASTPIN (-2750 1450) $PN F19
J 0
(-2740 1460);
DISPLAY 0.617021 (-2740 1460);
PAINT ORANGE (-2740 1460);
FORCEPROP 2 LASTPIN (-2750 1800) $PN F18
J 0
(-2740 1810);
DISPLAY 0.617021 (-2740 1810);
PAINT ORANGE (-2740 1810);
FORCEPROP 2 LASTPIN (-2750 2150) $PN F17
J 0
(-2740 2160);
DISPLAY 0.617021 (-2740 2160);
PAINT ORANGE (-2740 2160);
FORCEPROP 2 LASTPIN (-2750 2500) $PN F16
J 0
(-2740 2510);
DISPLAY 0.617021 (-2740 2510);
PAINT ORANGE (-2740 2510);
FORCEPROP 2 LASTPIN (-2750 2850) $PN F15
J 0
(-2740 2860);
DISPLAY 0.617021 (-2740 2860);
PAINT ORANGE (-2740 2860);
FORCEPROP 2 LASTPIN (-2750 3200) $PN F14
J 0
(-2740 3210);
DISPLAY 0.617021 (-2740 3210);
PAINT ORANGE (-2740 3210);
FORCEPROP 2 LASTPIN (-2750 3550) $PN F13
J 0
(-2740 3560);
DISPLAY 0.617021 (-2740 3560);
PAINT ORANGE (-2740 3560);
FORCEPROP 2 LASTPIN (-2750 3900) $PN F12
J 0
(-2740 3910);
DISPLAY 0.617021 (-2740 3910);
PAINT ORANGE (-2740 3910);
FORCEPROP 2 LASTPIN (-2750 4250) $PN F11
J 0
(-2740 4260);
DISPLAY 0.617021 (-2740 4260);
PAINT ORANGE (-2740 4260);
FORCEPROP 2 LASTPIN (-3550 1100) $PN F10
J 2
(-3560 1110);
DISPLAY 0.617021 (-3560 1110);
PAINT ORANGE (-3560 1110);
FORCEPROP 2 LASTPIN (-3550 1450) $PN F9
J 2
(-3560 1460);
DISPLAY 0.617021 (-3560 1460);
PAINT ORANGE (-3560 1460);
FORCEPROP 2 LASTPIN (-3550 1800) $PN F8
J 2
(-3560 1810);
DISPLAY 0.617021 (-3560 1810);
PAINT ORANGE (-3560 1810);
FORCEPROP 2 LASTPIN (-3550 2150) $PN F7
J 2
(-3560 2160);
DISPLAY 0.617021 (-3560 2160);
PAINT ORANGE (-3560 2160);
FORCEPROP 2 LASTPIN (-3550 2500) $PN F6
J 2
(-3560 2510);
DISPLAY 0.617021 (-3560 2510);
PAINT ORANGE (-3560 2510);
FORCEPROP 2 LASTPIN (-3550 2850) $PN F5
J 2
(-3560 2860);
DISPLAY 0.617021 (-3560 2860);
PAINT ORANGE (-3560 2860);
FORCEPROP 2 LASTPIN (-3550 3200) $PN F4
J 2
(-3560 3210);
DISPLAY 0.617021 (-3560 3210);
PAINT ORANGE (-3560 3210);
FORCEPROP 2 LASTPIN (-3550 3550) $PN F3
J 2
(-3560 3560);
DISPLAY 0.617021 (-3560 3560);
PAINT ORANGE (-3560 3560);
FORCEPROP 2 LASTPIN (-3550 3900) $PN F2
J 2
(-3560 3910);
DISPLAY 0.617021 (-3560 3910);
PAINT ORANGE (-3560 3910);
FORCEPROP 2 LASTPIN (-3550 4250) $PN F1
J 2
(-3560 4260);
DISPLAY 0.617021 (-3560 4260);
PAINT ORANGE (-3560 4260);
FORCEPROP 2 LASTPIN (-2750 1150) $PN E20
J 0
(-2740 1160);
DISPLAY 0.617021 (-2740 1160);
PAINT ORANGE (-2740 1160);
FORCEPROP 2 LASTPIN (-2750 1500) $PN E19
J 0
(-2740 1510);
DISPLAY 0.617021 (-2740 1510);
PAINT ORANGE (-2740 1510);
FORCEPROP 2 LASTPIN (-2750 1850) $PN E18
J 0
(-2740 1860);
DISPLAY 0.617021 (-2740 1860);
PAINT ORANGE (-2740 1860);
FORCEPROP 2 LASTPIN (-2750 2200) $PN E17
J 0
(-2740 2210);
DISPLAY 0.617021 (-2740 2210);
PAINT ORANGE (-2740 2210);
FORCEPROP 2 LASTPIN (-2750 2550) $PN E16
J 0
(-2740 2560);
DISPLAY 0.617021 (-2740 2560);
PAINT ORANGE (-2740 2560);
FORCEPROP 2 LASTPIN (-2750 2900) $PN E15
J 0
(-2740 2910);
DISPLAY 0.617021 (-2740 2910);
PAINT ORANGE (-2740 2910);
FORCEPROP 2 LASTPIN (-2750 3250) $PN E14
J 0
(-2740 3260);
DISPLAY 0.617021 (-2740 3260);
PAINT ORANGE (-2740 3260);
FORCEPROP 2 LASTPIN (-2750 3600) $PN E13
J 0
(-2740 3610);
DISPLAY 0.617021 (-2740 3610);
PAINT ORANGE (-2740 3610);
FORCEPROP 2 LASTPIN (-2750 3950) $PN E12
J 0
(-2740 3960);
DISPLAY 0.617021 (-2740 3960);
PAINT ORANGE (-2740 3960);
FORCEPROP 2 LASTPIN (-2750 4300) $PN E11
J 0
(-2740 4310);
DISPLAY 0.617021 (-2740 4310);
PAINT ORANGE (-2740 4310);
FORCEPROP 2 LASTPIN (-3550 1150) $PN E10
J 2
(-3560 1160);
DISPLAY 0.617021 (-3560 1160);
PAINT ORANGE (-3560 1160);
FORCEPROP 2 LASTPIN (-3550 1500) $PN E9
J 2
(-3560 1510);
DISPLAY 0.617021 (-3560 1510);
PAINT ORANGE (-3560 1510);
FORCEPROP 2 LASTPIN (-3550 1850) $PN E8
J 2
(-3560 1860);
DISPLAY 0.617021 (-3560 1860);
PAINT ORANGE (-3560 1860);
FORCEPROP 2 LASTPIN (-3550 2200) $PN E7
J 2
(-3560 2210);
DISPLAY 0.617021 (-3560 2210);
PAINT ORANGE (-3560 2210);
FORCEPROP 2 LASTPIN (-3550 2550) $PN E6
J 2
(-3560 2560);
DISPLAY 0.617021 (-3560 2560);
PAINT ORANGE (-3560 2560);
FORCEPROP 2 LASTPIN (-3550 2900) $PN E5
J 2
(-3560 2910);
DISPLAY 0.617021 (-3560 2910);
PAINT ORANGE (-3560 2910);
FORCEPROP 2 LASTPIN (-3550 3250) $PN E4
J 2
(-3560 3260);
DISPLAY 0.617021 (-3560 3260);
PAINT ORANGE (-3560 3260);
FORCEPROP 2 LASTPIN (-3550 3600) $PN E3
J 2
(-3560 3610);
DISPLAY 0.617021 (-3560 3610);
PAINT ORANGE (-3560 3610);
FORCEPROP 2 LASTPIN (-3550 3950) $PN E2
J 2
(-3560 3960);
DISPLAY 0.617021 (-3560 3960);
PAINT ORANGE (-3560 3960);
FORCEPROP 2 LASTPIN (-3550 4300) $PN E1
J 2
(-3560 4310);
DISPLAY 0.617021 (-3560 4310);
PAINT ORANGE (-3560 4310);
FORCEPROP 2 LASTPIN (-2750 1200) $PN D20
J 0
(-2740 1210);
DISPLAY 0.617021 (-2740 1210);
PAINT ORANGE (-2740 1210);
FORCEPROP 2 LASTPIN (-2750 1550) $PN D19
J 0
(-2740 1560);
DISPLAY 0.617021 (-2740 1560);
PAINT ORANGE (-2740 1560);
FORCEPROP 2 LASTPIN (-2750 1900) $PN D18
J 0
(-2740 1910);
DISPLAY 0.617021 (-2740 1910);
PAINT ORANGE (-2740 1910);
FORCEPROP 2 LASTPIN (-2750 2250) $PN D17
J 0
(-2740 2260);
DISPLAY 0.617021 (-2740 2260);
PAINT ORANGE (-2740 2260);
FORCEPROP 2 LASTPIN (-2750 2600) $PN D16
J 0
(-2740 2610);
DISPLAY 0.617021 (-2740 2610);
PAINT ORANGE (-2740 2610);
FORCEPROP 2 LASTPIN (-2750 2950) $PN D15
J 0
(-2740 2960);
DISPLAY 0.617021 (-2740 2960);
PAINT ORANGE (-2740 2960);
FORCEPROP 2 LASTPIN (-2750 3300) $PN D14
J 0
(-2740 3310);
DISPLAY 0.617021 (-2740 3310);
PAINT ORANGE (-2740 3310);
FORCEPROP 2 LASTPIN (-2750 3650) $PN D13
J 0
(-2740 3660);
DISPLAY 0.617021 (-2740 3660);
PAINT ORANGE (-2740 3660);
FORCEPROP 2 LASTPIN (-2750 4000) $PN D12
J 0
(-2740 4010);
DISPLAY 0.617021 (-2740 4010);
PAINT ORANGE (-2740 4010);
FORCEPROP 2 LASTPIN (-2750 4350) $PN D11
J 0
(-2740 4360);
DISPLAY 0.617021 (-2740 4360);
PAINT ORANGE (-2740 4360);
FORCEPROP 2 LASTPIN (-3550 1200) $PN D10
J 2
(-3560 1210);
DISPLAY 0.617021 (-3560 1210);
PAINT ORANGE (-3560 1210);
FORCEPROP 2 LASTPIN (-3550 1550) $PN D9
J 2
(-3560 1560);
DISPLAY 0.617021 (-3560 1560);
PAINT ORANGE (-3560 1560);
FORCEPROP 2 LASTPIN (-3550 1900) $PN D8
J 2
(-3560 1910);
DISPLAY 0.617021 (-3560 1910);
PAINT ORANGE (-3560 1910);
FORCEPROP 2 LASTPIN (-3550 2250) $PN D7
J 2
(-3560 2260);
DISPLAY 0.617021 (-3560 2260);
PAINT ORANGE (-3560 2260);
FORCEPROP 2 LASTPIN (-3550 2600) $PN D6
J 2
(-3560 2610);
DISPLAY 0.617021 (-3560 2610);
PAINT ORANGE (-3560 2610);
FORCEPROP 2 LASTPIN (-3550 2950) $PN D5
J 2
(-3560 2960);
DISPLAY 0.617021 (-3560 2960);
PAINT ORANGE (-3560 2960);
FORCEPROP 2 LASTPIN (-3550 3300) $PN D4
J 2
(-3560 3310);
DISPLAY 0.617021 (-3560 3310);
PAINT ORANGE (-3560 3310);
FORCEPROP 2 LASTPIN (-3550 3650) $PN D3
J 2
(-3560 3660);
DISPLAY 0.617021 (-3560 3660);
PAINT ORANGE (-3560 3660);
FORCEPROP 2 LASTPIN (-3550 4000) $PN D2
J 2
(-3560 4010);
DISPLAY 0.617021 (-3560 4010);
PAINT ORANGE (-3560 4010);
FORCEPROP 2 LASTPIN (-3550 4350) $PN D1
J 2
(-3560 4360);
DISPLAY 0.617021 (-3560 4360);
PAINT ORANGE (-3560 4360);
FORCEPROP 2 LASTPIN (-2750 1250) $PN C20
J 0
(-2740 1260);
DISPLAY 0.617021 (-2740 1260);
PAINT ORANGE (-2740 1260);
FORCEPROP 2 LASTPIN (-2750 1600) $PN C19
J 0
(-2740 1610);
DISPLAY 0.617021 (-2740 1610);
PAINT ORANGE (-2740 1610);
FORCEPROP 2 LASTPIN (-2750 1950) $PN C18
J 0
(-2740 1960);
DISPLAY 0.617021 (-2740 1960);
PAINT ORANGE (-2740 1960);
FORCEPROP 2 LASTPIN (-2750 2300) $PN C17
J 0
(-2740 2310);
DISPLAY 0.617021 (-2740 2310);
PAINT ORANGE (-2740 2310);
FORCEPROP 2 LASTPIN (-2750 2650) $PN C16
J 0
(-2740 2660);
DISPLAY 0.617021 (-2740 2660);
PAINT ORANGE (-2740 2660);
FORCEPROP 2 LASTPIN (-2750 3000) $PN C15
J 0
(-2740 3010);
DISPLAY 0.617021 (-2740 3010);
PAINT ORANGE (-2740 3010);
FORCEPROP 2 LASTPIN (-2750 3350) $PN C14
J 0
(-2740 3360);
DISPLAY 0.617021 (-2740 3360);
PAINT ORANGE (-2740 3360);
FORCEPROP 2 LASTPIN (-2750 3700) $PN C13
J 0
(-2740 3710);
DISPLAY 0.617021 (-2740 3710);
PAINT ORANGE (-2740 3710);
FORCEPROP 2 LASTPIN (-2750 4050) $PN C12
J 0
(-2740 4060);
DISPLAY 0.617021 (-2740 4060);
PAINT ORANGE (-2740 4060);
FORCEPROP 2 LASTPIN (-2750 4400) $PN C11
J 0
(-2740 4410);
DISPLAY 0.617021 (-2740 4410);
PAINT ORANGE (-2740 4410);
FORCEPROP 2 LASTPIN (-3550 1250) $PN C10
J 2
(-3560 1260);
DISPLAY 0.617021 (-3560 1260);
PAINT ORANGE (-3560 1260);
FORCEPROP 2 LASTPIN (-3550 1600) $PN C9
J 2
(-3560 1610);
DISPLAY 0.617021 (-3560 1610);
PAINT ORANGE (-3560 1610);
FORCEPROP 2 LASTPIN (-3550 1950) $PN C8
J 2
(-3560 1960);
DISPLAY 0.617021 (-3560 1960);
PAINT ORANGE (-3560 1960);
FORCEPROP 2 LASTPIN (-3550 2300) $PN C7
J 2
(-3560 2310);
DISPLAY 0.617021 (-3560 2310);
PAINT ORANGE (-3560 2310);
FORCEPROP 2 LASTPIN (-3550 2650) $PN C6
J 2
(-3560 2660);
DISPLAY 0.617021 (-3560 2660);
PAINT ORANGE (-3560 2660);
FORCEPROP 2 LASTPIN (-3550 3000) $PN C5
J 2
(-3560 3010);
DISPLAY 0.617021 (-3560 3010);
PAINT ORANGE (-3560 3010);
FORCEPROP 2 LASTPIN (-3550 3350) $PN C4
J 2
(-3560 3360);
DISPLAY 0.617021 (-3560 3360);
PAINT ORANGE (-3560 3360);
FORCEPROP 2 LASTPIN (-3550 3700) $PN C3
J 2
(-3560 3710);
DISPLAY 0.617021 (-3560 3710);
PAINT ORANGE (-3560 3710);
FORCEPROP 2 LASTPIN (-3550 4050) $PN C2
J 2
(-3560 4060);
DISPLAY 0.617021 (-3560 4060);
PAINT ORANGE (-3560 4060);
FORCEPROP 2 LASTPIN (-3550 4400) $PN C1
J 2
(-3560 4410);
DISPLAY 0.617021 (-3560 4410);
PAINT ORANGE (-3560 4410);
FORCEPROP 2 LASTPIN (-2750 1300) $PN B20
J 0
(-2740 1310);
DISPLAY 0.617021 (-2740 1310);
PAINT ORANGE (-2740 1310);
FORCEPROP 2 LASTPIN (-2750 1650) $PN B19
J 0
(-2740 1660);
DISPLAY 0.617021 (-2740 1660);
PAINT ORANGE (-2740 1660);
FORCEPROP 2 LASTPIN (-2750 2000) $PN B18
J 0
(-2740 2010);
DISPLAY 0.617021 (-2740 2010);
PAINT ORANGE (-2740 2010);
FORCEPROP 2 LASTPIN (-2750 2350) $PN B17
J 0
(-2740 2360);
DISPLAY 0.617021 (-2740 2360);
PAINT ORANGE (-2740 2360);
FORCEPROP 2 LASTPIN (-2750 2700) $PN B16
J 0
(-2740 2710);
DISPLAY 0.617021 (-2740 2710);
PAINT ORANGE (-2740 2710);
FORCEPROP 2 LASTPIN (-2750 3050) $PN B15
J 0
(-2740 3060);
DISPLAY 0.617021 (-2740 3060);
PAINT ORANGE (-2740 3060);
FORCEPROP 2 LASTPIN (-2750 3400) $PN B14
J 0
(-2740 3410);
DISPLAY 0.617021 (-2740 3410);
PAINT ORANGE (-2740 3410);
FORCEPROP 2 LASTPIN (-2750 3750) $PN B13
J 0
(-2740 3760);
DISPLAY 0.617021 (-2740 3760);
PAINT ORANGE (-2740 3760);
FORCEPROP 2 LASTPIN (-2750 4100) $PN B12
J 0
(-2740 4110);
DISPLAY 0.617021 (-2740 4110);
PAINT ORANGE (-2740 4110);
FORCEPROP 2 LASTPIN (-2750 4450) $PN B11
J 0
(-2740 4460);
DISPLAY 0.617021 (-2740 4460);
PAINT ORANGE (-2740 4460);
FORCEPROP 2 LASTPIN (-3550 1300) $PN B10
J 2
(-3560 1310);
DISPLAY 0.617021 (-3560 1310);
PAINT ORANGE (-3560 1310);
FORCEPROP 2 LASTPIN (-3550 1650) $PN B9
J 2
(-3560 1660);
DISPLAY 0.617021 (-3560 1660);
PAINT ORANGE (-3560 1660);
FORCEPROP 2 LASTPIN (-3550 2000) $PN B8
J 2
(-3560 2010);
DISPLAY 0.617021 (-3560 2010);
PAINT ORANGE (-3560 2010);
FORCEPROP 2 LASTPIN (-3550 2350) $PN B7
J 2
(-3560 2360);
DISPLAY 0.617021 (-3560 2360);
PAINT ORANGE (-3560 2360);
FORCEPROP 2 LASTPIN (-3550 2700) $PN B6
J 2
(-3560 2710);
DISPLAY 0.617021 (-3560 2710);
PAINT ORANGE (-3560 2710);
FORCEPROP 2 LASTPIN (-3550 3050) $PN B5
J 2
(-3560 3060);
DISPLAY 0.617021 (-3560 3060);
PAINT ORANGE (-3560 3060);
FORCEPROP 2 LASTPIN (-3550 3400) $PN B4
J 2
(-3560 3410);
DISPLAY 0.617021 (-3560 3410);
PAINT ORANGE (-3560 3410);
FORCEPROP 2 LASTPIN (-3550 3750) $PN B3
J 2
(-3560 3760);
DISPLAY 0.617021 (-3560 3760);
PAINT ORANGE (-3560 3760);
FORCEPROP 2 LASTPIN (-3550 4100) $PN B2
J 2
(-3560 4110);
DISPLAY 0.617021 (-3560 4110);
PAINT ORANGE (-3560 4110);
FORCEPROP 2 LASTPIN (-3550 4450) $PN B1
J 2
(-3560 4460);
DISPLAY 0.617021 (-3560 4460);
PAINT ORANGE (-3560 4460);
FORCEPROP 2 LASTPIN (-2750 1350) $PN A20
J 0
(-2740 1360);
DISPLAY 0.617021 (-2740 1360);
PAINT ORANGE (-2740 1360);
FORCEPROP 2 LASTPIN (-2750 1700) $PN A19
J 0
(-2740 1710);
DISPLAY 0.617021 (-2740 1710);
PAINT ORANGE (-2740 1710);
FORCEPROP 2 LASTPIN (-2750 2050) $PN A18
J 0
(-2740 2060);
DISPLAY 0.617021 (-2740 2060);
PAINT ORANGE (-2740 2060);
FORCEPROP 2 LASTPIN (-2750 2400) $PN A17
J 0
(-2740 2410);
DISPLAY 0.617021 (-2740 2410);
PAINT ORANGE (-2740 2410);
FORCEPROP 2 LASTPIN (-2750 2750) $PN A16
J 0
(-2740 2760);
DISPLAY 0.617021 (-2740 2760);
PAINT ORANGE (-2740 2760);
FORCEPROP 2 LASTPIN (-2750 3100) $PN A15
J 0
(-2740 3110);
DISPLAY 0.617021 (-2740 3110);
PAINT ORANGE (-2740 3110);
FORCEPROP 2 LASTPIN (-2750 3450) $PN A14
J 0
(-2740 3460);
DISPLAY 0.617021 (-2740 3460);
PAINT ORANGE (-2740 3460);
FORCEPROP 2 LASTPIN (-2750 3800) $PN A13
J 0
(-2740 3810);
DISPLAY 0.617021 (-2740 3810);
PAINT ORANGE (-2740 3810);
FORCEPROP 2 LASTPIN (-2750 4150) $PN A12
J 0
(-2740 4160);
DISPLAY 0.617021 (-2740 4160);
PAINT ORANGE (-2740 4160);
FORCEPROP 2 LASTPIN (-2750 4500) $PN A11
J 0
(-2740 4510);
DISPLAY 0.617021 (-2740 4510);
PAINT ORANGE (-2740 4510);
FORCEPROP 2 LASTPIN (-3550 1350) $PN A10
J 2
(-3560 1360);
DISPLAY 0.617021 (-3560 1360);
PAINT ORANGE (-3560 1360);
FORCEPROP 2 LASTPIN (-3550 1700) $PN A9
J 2
(-3560 1710);
DISPLAY 0.617021 (-3560 1710);
PAINT ORANGE (-3560 1710);
FORCEPROP 2 LASTPIN (-3550 2050) $PN A8
J 2
(-3560 2060);
DISPLAY 0.617021 (-3560 2060);
PAINT ORANGE (-3560 2060);
FORCEPROP 2 LASTPIN (-3550 2400) $PN A7
J 2
(-3560 2410);
DISPLAY 0.617021 (-3560 2410);
PAINT ORANGE (-3560 2410);
FORCEPROP 2 LASTPIN (-3550 2750) $PN A6
J 2
(-3560 2760);
DISPLAY 0.617021 (-3560 2760);
PAINT ORANGE (-3560 2760);
FORCEPROP 2 LASTPIN (-3550 3100) $PN A5
J 2
(-3560 3110);
DISPLAY 0.617021 (-3560 3110);
PAINT ORANGE (-3560 3110);
FORCEPROP 2 LASTPIN (-3550 3450) $PN A4
J 2
(-3560 3460);
DISPLAY 0.617021 (-3560 3460);
PAINT ORANGE (-3560 3460);
FORCEPROP 2 LASTPIN (-3550 3800) $PN A3
J 2
(-3560 3810);
DISPLAY 0.617021 (-3560 3810);
PAINT ORANGE (-3560 3810);
FORCEPROP 2 LASTPIN (-3550 4150) $PN A2
J 2
(-3560 4160);
DISPLAY 0.617021 (-3560 4160);
PAINT ORANGE (-3560 4160);
FORCEPROP 2 LASTPIN (-3550 4500) $PN A1
J 2
(-3560 4510);
DISPLAY 0.617021 (-3560 4510);
PAINT ORANGE (-3560 4510);
FORCEPROP 1 LAST PACK_TYPE SM
J 0
(-3500 4850);
PAINT SKYBLUE (-3500 4850);
DISPLAY INVISIBLE (-3500 4850);
FORCEPROP 2 LAST CDS_LIB mstr_sconn
J 0
(-3150 2800);
PAINT ORANGE (-3150 2800);
DISPLAY INVISIBLE (-3150 2800);
FORCEPROP 2 LAST SEC_TYPE SM
J 0
(-3500 4850);
DISPLAY 1.021277 (-3500 4850);
PAINT ORANGE (-3500 4850);
DISPLAY INVISIBLE (-3500 4850);
FORCEPROP 2 LAST SEC 1
J 0
(-3500 4850);
DISPLAY 0.680851 (-3500 4850);
PAINT MONO (-3500 4850);
DISPLAY INVISIBLE (-3500 4850);
FORCEPROP 2 LAST CDS_LOCATION J4E1
J 0
(-3500 4800);
DISPLAY 0.617021 (-3500 4800);
PAINT AQUA (-3500 4800);
DISPLAY INVISIBLE (-3500 4800);
FORCEPROP 1 LAST PATH I45
J 0
(-3100 4750);
PAINT GREEN (-3100 4750);
DISPLAY INVISIBLE (-3100 4750);
FORCEPROP 0 LAST ROOM MCP VRM CPU1
J 0
(-3500 4900);
DISPLAY 1.021277 (-3500 4900);
PAINT ORANGE (-3500 4900);
DISPLAY INVISIBLE (-3500 4900);
FORCEADD SCONN120_H61426002..1
(-6325 2725);
FORCEPROP 1 LAST LOCATION J4B2
J 0
(-6675 4725);
DISPLAY 0.617021 (-6675 4725);
PAINT AQUA (-6675 4725);
FORCEPROP 1 LAST PART_NUMBER H61426-002
J 0
(-6675 825);
DISPLAY 0.617021 (-6675 825);
PAINT BLUE (-6675 825);
FORCEPROP 1 LAST MATERIAL CONN
J 0
(-6675 4675);
DISPLAY 0.617021 (-6675 4675);
PAINT SKYBLUE (-6675 4675);
FORCEPROP 2 LASTPIN (-5925 1025) $PN F20
J 0
(-5915 1035);
DISPLAY 0.617021 (-5915 1035);
PAINT ORANGE (-5915 1035);
FORCEPROP 2 LASTPIN (-5925 1375) $PN F19
J 0
(-5915 1385);
DISPLAY 0.617021 (-5915 1385);
PAINT ORANGE (-5915 1385);
FORCEPROP 2 LASTPIN (-5925 1725) $PN F18
J 0
(-5915 1735);
DISPLAY 0.617021 (-5915 1735);
PAINT ORANGE (-5915 1735);
FORCEPROP 2 LASTPIN (-5925 2075) $PN F17
J 0
(-5915 2085);
DISPLAY 0.617021 (-5915 2085);
PAINT ORANGE (-5915 2085);
FORCEPROP 2 LASTPIN (-5925 2425) $PN F16
J 0
(-5915 2435);
DISPLAY 0.617021 (-5915 2435);
PAINT ORANGE (-5915 2435);
FORCEPROP 2 LASTPIN (-5925 2775) $PN F15
J 0
(-5915 2785);
DISPLAY 0.617021 (-5915 2785);
PAINT ORANGE (-5915 2785);
FORCEPROP 2 LASTPIN (-5925 3125) $PN F14
J 0
(-5915 3135);
DISPLAY 0.617021 (-5915 3135);
PAINT ORANGE (-5915 3135);
FORCEPROP 2 LASTPIN (-5925 3475) $PN F13
J 0
(-5915 3485);
DISPLAY 0.617021 (-5915 3485);
PAINT ORANGE (-5915 3485);
FORCEPROP 2 LASTPIN (-5925 3825) $PN F12
J 0
(-5915 3835);
DISPLAY 0.617021 (-5915 3835);
PAINT ORANGE (-5915 3835);
FORCEPROP 2 LASTPIN (-5925 4175) $PN F11
J 0
(-5915 4185);
DISPLAY 0.617021 (-5915 4185);
PAINT ORANGE (-5915 4185);
FORCEPROP 2 LASTPIN (-6725 1025) $PN F10
J 2
(-6735 1035);
DISPLAY 0.617021 (-6735 1035);
PAINT ORANGE (-6735 1035);
FORCEPROP 2 LASTPIN (-6725 1375) $PN F9
J 2
(-6735 1385);
DISPLAY 0.617021 (-6735 1385);
PAINT ORANGE (-6735 1385);
FORCEPROP 2 LASTPIN (-6725 1725) $PN F8
J 2
(-6735 1735);
DISPLAY 0.617021 (-6735 1735);
PAINT ORANGE (-6735 1735);
FORCEPROP 2 LASTPIN (-6725 2075) $PN F7
J 2
(-6735 2085);
DISPLAY 0.617021 (-6735 2085);
PAINT ORANGE (-6735 2085);
FORCEPROP 2 LASTPIN (-6725 2425) $PN F6
J 2
(-6735 2435);
DISPLAY 0.617021 (-6735 2435);
PAINT ORANGE (-6735 2435);
FORCEPROP 2 LASTPIN (-6725 2775) $PN F5
J 2
(-6735 2785);
DISPLAY 0.617021 (-6735 2785);
PAINT ORANGE (-6735 2785);
FORCEPROP 2 LASTPIN (-6725 3125) $PN F4
J 2
(-6735 3135);
DISPLAY 0.617021 (-6735 3135);
PAINT ORANGE (-6735 3135);
FORCEPROP 2 LASTPIN (-6725 3475) $PN F3
J 2
(-6735 3485);
DISPLAY 0.617021 (-6735 3485);
PAINT ORANGE (-6735 3485);
FORCEPROP 2 LASTPIN (-6725 3825) $PN F2
J 2
(-6735 3835);
DISPLAY 0.617021 (-6735 3835);
PAINT ORANGE (-6735 3835);
FORCEPROP 2 LASTPIN (-6725 4175) $PN F1
J 2
(-6735 4185);
DISPLAY 0.617021 (-6735 4185);
PAINT ORANGE (-6735 4185);
FORCEPROP 2 LASTPIN (-5925 1075) $PN E20
J 0
(-5915 1085);
DISPLAY 0.617021 (-5915 1085);
PAINT ORANGE (-5915 1085);
FORCEPROP 2 LASTPIN (-5925 1425) $PN E19
J 0
(-5915 1435);
DISPLAY 0.617021 (-5915 1435);
PAINT ORANGE (-5915 1435);
FORCEPROP 2 LASTPIN (-5925 1775) $PN E18
J 0
(-5915 1785);
DISPLAY 0.617021 (-5915 1785);
PAINT ORANGE (-5915 1785);
FORCEPROP 2 LASTPIN (-5925 2125) $PN E17
J 0
(-5915 2135);
DISPLAY 0.617021 (-5915 2135);
PAINT ORANGE (-5915 2135);
FORCEPROP 2 LASTPIN (-5925 2475) $PN E16
J 0
(-5915 2485);
DISPLAY 0.617021 (-5915 2485);
PAINT ORANGE (-5915 2485);
FORCEPROP 2 LASTPIN (-5925 2825) $PN E15
J 0
(-5915 2835);
DISPLAY 0.617021 (-5915 2835);
PAINT ORANGE (-5915 2835);
FORCEPROP 2 LASTPIN (-5925 3175) $PN E14
J 0
(-5915 3185);
DISPLAY 0.617021 (-5915 3185);
PAINT ORANGE (-5915 3185);
FORCEPROP 2 LASTPIN (-5925 3525) $PN E13
J 0
(-5915 3535);
DISPLAY 0.617021 (-5915 3535);
PAINT ORANGE (-5915 3535);
FORCEPROP 2 LASTPIN (-5925 3875) $PN E12
J 0
(-5915 3885);
DISPLAY 0.617021 (-5915 3885);
PAINT ORANGE (-5915 3885);
FORCEPROP 2 LASTPIN (-5925 4225) $PN E11
J 0
(-5915 4235);
DISPLAY 0.617021 (-5915 4235);
PAINT ORANGE (-5915 4235);
FORCEPROP 2 LASTPIN (-6725 1075) $PN E10
J 2
(-6735 1085);
DISPLAY 0.617021 (-6735 1085);
PAINT ORANGE (-6735 1085);
FORCEPROP 2 LASTPIN (-6725 1425) $PN E9
J 2
(-6735 1435);
DISPLAY 0.617021 (-6735 1435);
PAINT ORANGE (-6735 1435);
FORCEPROP 2 LASTPIN (-6725 1775) $PN E8
J 2
(-6735 1785);
DISPLAY 0.617021 (-6735 1785);
PAINT ORANGE (-6735 1785);
FORCEPROP 2 LASTPIN (-6725 2125) $PN E7
J 2
(-6735 2135);
DISPLAY 0.617021 (-6735 2135);
PAINT ORANGE (-6735 2135);
FORCEPROP 2 LASTPIN (-6725 2475) $PN E6
J 2
(-6735 2485);
DISPLAY 0.617021 (-6735 2485);
PAINT ORANGE (-6735 2485);
FORCEPROP 2 LASTPIN (-6725 2825) $PN E5
J 2
(-6735 2835);
DISPLAY 0.617021 (-6735 2835);
PAINT ORANGE (-6735 2835);
FORCEPROP 2 LASTPIN (-6725 3175) $PN E4
J 2
(-6735 3185);
DISPLAY 0.617021 (-6735 3185);
PAINT ORANGE (-6735 3185);
FORCEPROP 2 LASTPIN (-6725 3525) $PN E3
J 2
(-6735 3535);
DISPLAY 0.617021 (-6735 3535);
PAINT ORANGE (-6735 3535);
FORCEPROP 2 LASTPIN (-6725 3875) $PN E2
J 2
(-6735 3885);
DISPLAY 0.617021 (-6735 3885);
PAINT ORANGE (-6735 3885);
FORCEPROP 2 LASTPIN (-6725 4225) $PN E1
J 2
(-6735 4235);
DISPLAY 0.617021 (-6735 4235);
PAINT ORANGE (-6735 4235);
FORCEPROP 2 LASTPIN (-5925 1125) $PN D20
J 0
(-5915 1135);
DISPLAY 0.617021 (-5915 1135);
PAINT ORANGE (-5915 1135);
FORCEPROP 2 LASTPIN (-5925 1475) $PN D19
J 0
(-5915 1485);
DISPLAY 0.617021 (-5915 1485);
PAINT ORANGE (-5915 1485);
FORCEPROP 2 LASTPIN (-5925 1825) $PN D18
J 0
(-5915 1835);
DISPLAY 0.617021 (-5915 1835);
PAINT ORANGE (-5915 1835);
FORCEPROP 2 LASTPIN (-5925 2175) $PN D17
J 0
(-5915 2185);
DISPLAY 0.617021 (-5915 2185);
PAINT ORANGE (-5915 2185);
FORCEPROP 2 LASTPIN (-5925 2525) $PN D16
J 0
(-5915 2535);
DISPLAY 0.617021 (-5915 2535);
PAINT ORANGE (-5915 2535);
FORCEPROP 2 LASTPIN (-5925 2875) $PN D15
J 0
(-5915 2885);
DISPLAY 0.617021 (-5915 2885);
PAINT ORANGE (-5915 2885);
FORCEPROP 2 LASTPIN (-5925 3225) $PN D14
J 0
(-5915 3235);
DISPLAY 0.617021 (-5915 3235);
PAINT ORANGE (-5915 3235);
FORCEPROP 2 LASTPIN (-5925 3575) $PN D13
J 0
(-5915 3585);
DISPLAY 0.617021 (-5915 3585);
PAINT ORANGE (-5915 3585);
FORCEPROP 2 LASTPIN (-5925 3925) $PN D12
J 0
(-5915 3935);
DISPLAY 0.617021 (-5915 3935);
PAINT ORANGE (-5915 3935);
FORCEPROP 2 LASTPIN (-5925 4275) $PN D11
J 0
(-5915 4285);
DISPLAY 0.617021 (-5915 4285);
PAINT ORANGE (-5915 4285);
FORCEPROP 2 LASTPIN (-6725 1125) $PN D10
J 2
(-6735 1135);
DISPLAY 0.617021 (-6735 1135);
PAINT ORANGE (-6735 1135);
FORCEPROP 2 LASTPIN (-6725 1475) $PN D9
J 2
(-6735 1485);
DISPLAY 0.617021 (-6735 1485);
PAINT ORANGE (-6735 1485);
FORCEPROP 2 LASTPIN (-6725 1825) $PN D8
J 2
(-6735 1835);
DISPLAY 0.617021 (-6735 1835);
PAINT ORANGE (-6735 1835);
FORCEPROP 2 LASTPIN (-6725 2175) $PN D7
J 2
(-6735 2185);
DISPLAY 0.617021 (-6735 2185);
PAINT ORANGE (-6735 2185);
FORCEPROP 2 LASTPIN (-6725 2525) $PN D6
J 2
(-6735 2535);
DISPLAY 0.617021 (-6735 2535);
PAINT ORANGE (-6735 2535);
FORCEPROP 2 LASTPIN (-6725 2875) $PN D5
J 2
(-6735 2885);
DISPLAY 0.617021 (-6735 2885);
PAINT ORANGE (-6735 2885);
FORCEPROP 2 LASTPIN (-6725 3225) $PN D4
J 2
(-6735 3235);
DISPLAY 0.617021 (-6735 3235);
PAINT ORANGE (-6735 3235);
FORCEPROP 2 LASTPIN (-6725 3575) $PN D3
J 2
(-6735 3585);
DISPLAY 0.617021 (-6735 3585);
PAINT ORANGE (-6735 3585);
FORCEPROP 2 LASTPIN (-6725 3925) $PN D2
J 2
(-6735 3935);
DISPLAY 0.617021 (-6735 3935);
PAINT ORANGE (-6735 3935);
FORCEPROP 2 LASTPIN (-6725 4275) $PN D1
J 2
(-6735 4285);
DISPLAY 0.617021 (-6735 4285);
PAINT ORANGE (-6735 4285);
FORCEPROP 2 LASTPIN (-5925 1175) $PN C20
J 0
(-5915 1185);
DISPLAY 0.617021 (-5915 1185);
PAINT ORANGE (-5915 1185);
FORCEPROP 2 LASTPIN (-5925 1525) $PN C19
J 0
(-5915 1535);
DISPLAY 0.617021 (-5915 1535);
PAINT ORANGE (-5915 1535);
FORCEPROP 2 LASTPIN (-5925 1875) $PN C18
J 0
(-5915 1885);
DISPLAY 0.617021 (-5915 1885);
PAINT ORANGE (-5915 1885);
FORCEPROP 2 LASTPIN (-5925 2225) $PN C17
J 0
(-5915 2235);
DISPLAY 0.617021 (-5915 2235);
PAINT ORANGE (-5915 2235);
FORCEPROP 2 LASTPIN (-5925 2575) $PN C16
J 0
(-5915 2585);
DISPLAY 0.617021 (-5915 2585);
PAINT ORANGE (-5915 2585);
FORCEPROP 2 LASTPIN (-5925 2925) $PN C15
J 0
(-5915 2935);
DISPLAY 0.617021 (-5915 2935);
PAINT ORANGE (-5915 2935);
FORCEPROP 2 LASTPIN (-5925 3275) $PN C14
J 0
(-5915 3285);
DISPLAY 0.617021 (-5915 3285);
PAINT ORANGE (-5915 3285);
FORCEPROP 2 LASTPIN (-5925 3625) $PN C13
J 0
(-5915 3635);
DISPLAY 0.617021 (-5915 3635);
PAINT ORANGE (-5915 3635);
FORCEPROP 2 LASTPIN (-5925 3975) $PN C12
J 0
(-5915 3985);
DISPLAY 0.617021 (-5915 3985);
PAINT ORANGE (-5915 3985);
FORCEPROP 2 LASTPIN (-5925 4325) $PN C11
J 0
(-5915 4335);
DISPLAY 0.617021 (-5915 4335);
PAINT ORANGE (-5915 4335);
FORCEPROP 2 LASTPIN (-6725 1175) $PN C10
J 2
(-6735 1185);
DISPLAY 0.617021 (-6735 1185);
PAINT ORANGE (-6735 1185);
FORCEPROP 2 LASTPIN (-6725 1525) $PN C9
J 2
(-6735 1535);
DISPLAY 0.617021 (-6735 1535);
PAINT ORANGE (-6735 1535);
FORCEPROP 2 LASTPIN (-6725 1875) $PN C8
J 2
(-6735 1885);
DISPLAY 0.617021 (-6735 1885);
PAINT ORANGE (-6735 1885);
FORCEPROP 2 LASTPIN (-6725 2225) $PN C7
J 2
(-6735 2235);
DISPLAY 0.617021 (-6735 2235);
PAINT ORANGE (-6735 2235);
FORCEPROP 2 LASTPIN (-6725 2575) $PN C6
J 2
(-6735 2585);
DISPLAY 0.617021 (-6735 2585);
PAINT ORANGE (-6735 2585);
FORCEPROP 2 LASTPIN (-6725 2925) $PN C5
J 2
(-6735 2935);
DISPLAY 0.617021 (-6735 2935);
PAINT ORANGE (-6735 2935);
FORCEPROP 2 LASTPIN (-6725 3275) $PN C4
J 2
(-6735 3285);
DISPLAY 0.617021 (-6735 3285);
PAINT ORANGE (-6735 3285);
FORCEPROP 2 LASTPIN (-6725 3625) $PN C3
J 2
(-6735 3635);
DISPLAY 0.617021 (-6735 3635);
PAINT ORANGE (-6735 3635);
FORCEPROP 2 LASTPIN (-6725 3975) $PN C2
J 2
(-6735 3985);
DISPLAY 0.617021 (-6735 3985);
PAINT ORANGE (-6735 3985);
FORCEPROP 2 LASTPIN (-6725 4325) $PN C1
J 2
(-6735 4335);
DISPLAY 0.617021 (-6735 4335);
PAINT ORANGE (-6735 4335);
FORCEPROP 2 LASTPIN (-5925 1225) $PN B20
J 0
(-5915 1235);
DISPLAY 0.617021 (-5915 1235);
PAINT ORANGE (-5915 1235);
FORCEPROP 2 LASTPIN (-5925 1575) $PN B19
J 0
(-5915 1585);
DISPLAY 0.617021 (-5915 1585);
PAINT ORANGE (-5915 1585);
FORCEPROP 2 LASTPIN (-5925 1925) $PN B18
J 0
(-5915 1935);
DISPLAY 0.617021 (-5915 1935);
PAINT ORANGE (-5915 1935);
FORCEPROP 2 LASTPIN (-5925 2275) $PN B17
J 0
(-5915 2285);
DISPLAY 0.617021 (-5915 2285);
PAINT ORANGE (-5915 2285);
FORCEPROP 2 LASTPIN (-5925 2625) $PN B16
J 0
(-5915 2635);
DISPLAY 0.617021 (-5915 2635);
PAINT ORANGE (-5915 2635);
FORCEPROP 2 LASTPIN (-5925 2975) $PN B15
J 0
(-5915 2985);
DISPLAY 0.617021 (-5915 2985);
PAINT ORANGE (-5915 2985);
FORCEPROP 2 LASTPIN (-5925 3325) $PN B14
J 0
(-5915 3335);
DISPLAY 0.617021 (-5915 3335);
PAINT ORANGE (-5915 3335);
FORCEPROP 2 LASTPIN (-5925 3675) $PN B13
J 0
(-5915 3685);
DISPLAY 0.617021 (-5915 3685);
PAINT ORANGE (-5915 3685);
FORCEPROP 2 LASTPIN (-5925 4025) $PN B12
J 0
(-5915 4035);
DISPLAY 0.617021 (-5915 4035);
PAINT ORANGE (-5915 4035);
FORCEPROP 2 LASTPIN (-5925 4375) $PN B11
J 0
(-5915 4385);
DISPLAY 0.617021 (-5915 4385);
PAINT ORANGE (-5915 4385);
FORCEPROP 2 LASTPIN (-6725 1225) $PN B10
J 2
(-6735 1235);
DISPLAY 0.617021 (-6735 1235);
PAINT ORANGE (-6735 1235);
FORCEPROP 2 LASTPIN (-6725 1575) $PN B9
J 2
(-6735 1585);
DISPLAY 0.617021 (-6735 1585);
PAINT ORANGE (-6735 1585);
FORCEPROP 2 LASTPIN (-6725 1925) $PN B8
J 2
(-6735 1935);
DISPLAY 0.617021 (-6735 1935);
PAINT ORANGE (-6735 1935);
FORCEPROP 2 LASTPIN (-6725 2275) $PN B7
J 2
(-6735 2285);
DISPLAY 0.617021 (-6735 2285);
PAINT ORANGE (-6735 2285);
FORCEPROP 2 LASTPIN (-6725 2625) $PN B6
J 2
(-6735 2635);
DISPLAY 0.617021 (-6735 2635);
PAINT ORANGE (-6735 2635);
FORCEPROP 2 LASTPIN (-6725 2975) $PN B5
J 2
(-6735 2985);
DISPLAY 0.617021 (-6735 2985);
PAINT ORANGE (-6735 2985);
FORCEPROP 2 LASTPIN (-6725 3325) $PN B4
J 2
(-6735 3335);
DISPLAY 0.617021 (-6735 3335);
PAINT ORANGE (-6735 3335);
FORCEPROP 2 LASTPIN (-6725 3675) $PN B3
J 2
(-6735 3685);
DISPLAY 0.617021 (-6735 3685);
PAINT ORANGE (-6735 3685);
FORCEPROP 2 LASTPIN (-6725 4025) $PN B2
J 2
(-6735 4035);
DISPLAY 0.617021 (-6735 4035);
PAINT ORANGE (-6735 4035);
FORCEPROP 2 LASTPIN (-6725 4375) $PN B1
J 2
(-6735 4385);
DISPLAY 0.617021 (-6735 4385);
PAINT ORANGE (-6735 4385);
FORCEPROP 2 LASTPIN (-5925 1275) $PN A20
J 0
(-5915 1285);
DISPLAY 0.617021 (-5915 1285);
PAINT ORANGE (-5915 1285);
FORCEPROP 2 LASTPIN (-5925 1625) $PN A19
J 0
(-5915 1635);
DISPLAY 0.617021 (-5915 1635);
PAINT ORANGE (-5915 1635);
FORCEPROP 2 LASTPIN (-5925 1975) $PN A18
J 0
(-5915 1985);
DISPLAY 0.617021 (-5915 1985);
PAINT ORANGE (-5915 1985);
FORCEPROP 2 LASTPIN (-5925 2325) $PN A17
J 0
(-5915 2335);
DISPLAY 0.617021 (-5915 2335);
PAINT ORANGE (-5915 2335);
FORCEPROP 2 LASTPIN (-5925 2675) $PN A16
J 0
(-5915 2685);
DISPLAY 0.617021 (-5915 2685);
PAINT ORANGE (-5915 2685);
FORCEPROP 2 LASTPIN (-5925 3025) $PN A15
J 0
(-5915 3035);
DISPLAY 0.617021 (-5915 3035);
PAINT ORANGE (-5915 3035);
FORCEPROP 2 LASTPIN (-5925 3375) $PN A14
J 0
(-5915 3385);
DISPLAY 0.617021 (-5915 3385);
PAINT ORANGE (-5915 3385);
FORCEPROP 2 LASTPIN (-5925 3725) $PN A13
J 0
(-5915 3735);
DISPLAY 0.617021 (-5915 3735);
PAINT ORANGE (-5915 3735);
FORCEPROP 2 LASTPIN (-5925 4075) $PN A12
J 0
(-5915 4085);
DISPLAY 0.617021 (-5915 4085);
PAINT ORANGE (-5915 4085);
FORCEPROP 2 LASTPIN (-5925 4425) $PN A11
J 0
(-5915 4435);
DISPLAY 0.617021 (-5915 4435);
PAINT ORANGE (-5915 4435);
FORCEPROP 2 LASTPIN (-6725 1275) $PN A10
J 2
(-6735 1285);
DISPLAY 0.617021 (-6735 1285);
PAINT ORANGE (-6735 1285);
FORCEPROP 2 LASTPIN (-6725 1625) $PN A9
J 2
(-6735 1635);
DISPLAY 0.617021 (-6735 1635);
PAINT ORANGE (-6735 1635);
FORCEPROP 2 LASTPIN (-6725 1975) $PN A8
J 2
(-6735 1985);
DISPLAY 0.617021 (-6735 1985);
PAINT ORANGE (-6735 1985);
FORCEPROP 2 LASTPIN (-6725 2325) $PN A7
J 2
(-6735 2335);
DISPLAY 0.617021 (-6735 2335);
PAINT ORANGE (-6735 2335);
FORCEPROP 2 LASTPIN (-6725 2675) $PN A6
J 2
(-6735 2685);
DISPLAY 0.617021 (-6735 2685);
PAINT ORANGE (-6735 2685);
FORCEPROP 2 LASTPIN (-6725 3025) $PN A5
J 2
(-6735 3035);
DISPLAY 0.617021 (-6735 3035);
PAINT ORANGE (-6735 3035);
FORCEPROP 2 LASTPIN (-6725 3375) $PN A4
J 2
(-6735 3385);
DISPLAY 0.617021 (-6735 3385);
PAINT ORANGE (-6735 3385);
FORCEPROP 2 LASTPIN (-6725 3725) $PN A3
J 2
(-6735 3735);
DISPLAY 0.617021 (-6735 3735);
PAINT ORANGE (-6735 3735);
FORCEPROP 2 LASTPIN (-6725 4075) $PN A2
J 2
(-6735 4085);
DISPLAY 0.617021 (-6735 4085);
PAINT ORANGE (-6735 4085);
FORCEPROP 2 LASTPIN (-6725 4425) $PN A1
J 2
(-6735 4435);
DISPLAY 0.617021 (-6735 4435);
PAINT ORANGE (-6735 4435);
FORCEPROP 1 LAST PACK_TYPE SM
J 0
(-6675 4775);
PAINT SKYBLUE (-6675 4775);
DISPLAY INVISIBLE (-6675 4775);
FORCEPROP 2 LAST CDS_LIB mstr_sconn
J 0
(-6325 2725);
PAINT ORANGE (-6325 2725);
DISPLAY INVISIBLE (-6325 2725);
FORCEPROP 2 LAST SEC_TYPE SM
J 0
(-6675 4775);
DISPLAY 1.021277 (-6675 4775);
PAINT ORANGE (-6675 4775);
DISPLAY INVISIBLE (-6675 4775);
FORCEPROP 2 LAST SEC 1
J 0
(-6675 4775);
DISPLAY 0.680851 (-6675 4775);
PAINT MONO (-6675 4775);
DISPLAY INVISIBLE (-6675 4775);
FORCEPROP 2 LAST CDS_LOCATION J4B2
J 0
(-6675 4725);
DISPLAY 0.617021 (-6675 4725);
PAINT AQUA (-6675 4725);
DISPLAY INVISIBLE (-6675 4725);
FORCEPROP 1 LAST PATH I46
J 0
(-6275 4675);
PAINT GREEN (-6275 4675);
DISPLAY INVISIBLE (-6275 4675);
FORCEPROP 0 LAST ROOM MCP VRM CPU1
J 0
(-6675 4825);
DISPLAY 1.021277 (-6675 4825);
PAINT ORANGE (-6675 4825);
DISPLAY INVISIBLE (-6675 4825);
FORCEADD OFFPAGE..1
(-4750 3400);
FORCEPROP 2 LAST $XR0 73 
J 0
(-5001 3400);
DISPLAY 0.638298 (-5001 3400);
PAINT MONO (-5001 3400);
FORCEPROP 2 LAST CDS_LIB mstr_standard
J 0
(-4750 3400);
PAINT MONO (-4750 3400);
DISPLAY INVISIBLE (-4750 3400);
FORCEPROP 1 LAST OFFPAGE TRUE
J 0
(-4425 3275);
DISPLAY 1.170213 (-4425 3275);
PAINT GREEN (-4425 3275);
DISPLAY INVISIBLE (-4425 3275);
FORCEPROP 1 LAST COMMENT_BODY TRUE
J 0
(-4625 3300);
DISPLAY 1.170213 (-4625 3300);
PAINT GREEN (-4625 3300);
DISPLAY INVISIBLE (-4625 3300);
FORCEPROP 2 LAST PATH I49
J 0
(-4700 3475);
DISPLAY 1.021277 (-4700 3475);
PAINT ORANGE (-4700 3475);
DISPLAY INVISIBLE (-4700 3475);
FORCEADD OFFPAGE..1
R 2
(-5150 1975);
FORCEPROP 2 LAST $XR0 138 
J 0
(-4964 1975);
DISPLAY 0.638298 (-4964 1975);
PAINT MONO (-4964 1975);
FORCEPROP 2 LAST $XR1 159 
J 0
(-4844 1975);
DISPLAY 0.638298 (-4844 1975);
PAINT MONO (-4844 1975);
FORCEPROP 2 LAST $XR2 211 
J 0
(-4724 1975);
DISPLAY 0.638298 (-4724 1975);
PAINT MONO (-4724 1975);
FORCEPROP 2 LAST $XR3 213 
J 0
(-4604 1975);
DISPLAY 0.638298 (-4604 1975);
PAINT MONO (-4604 1975);
FORCEPROP 2 LAST $XR4 235 
J 0
(-4484 1975);
DISPLAY 0.638298 (-4484 1975);
PAINT MONO (-4484 1975);
FORCEPROP 2 LAST $XR5 194 
J 0
(-4364 1975);
DISPLAY 0.638298 (-4364 1975);
PAINT MONO (-4364 1975);
FORCEPROP 2 LAST $XR6 201 
J 0
(-4244 1975);
DISPLAY 0.638298 (-4244 1975);
PAINT MONO (-4244 1975);
FORCEPROP 2 LAST $XR7 206 
J 0
(-4124 1975);
DISPLAY 0.638298 (-4124 1975);
PAINT MONO (-4124 1975);
FORCEPROP 2 LAST $XR8 215 
J 0
(-4964 2011);
DISPLAY 0.638298 (-4964 2011);
PAINT MONO (-4964 2011);
FORCEPROP 2 LAST $XR9 218 
J 0
(-4844 2011);
DISPLAY 0.638298 (-4844 2011);
PAINT MONO (-4844 2011);
FORCEPROP 2 LAST $XR10 223 
J 0
(-4724 2011);
DISPLAY 0.638298 (-4724 2011);
PAINT MONO (-4724 2011);
FORCEPROP 2 LAST $XR11 226 
J 0
(-4604 2011);
DISPLAY 0.638298 (-4604 2011);
PAINT MONO (-4604 2011);
FORCEPROP 2 LAST ROOM P0V95_FPGA_CPU0_VR
J 0
(-5575 2050);
DISPLAY 1.361702 (-5575 2050);
PAINT ORANGE (-5575 2050);
DISPLAY INVISIBLE (-5575 2050);
FORCEPROP 2 LAST CDS_LIB mstr_standard
J 0
(-5150 1975);
PAINT ORANGE (-5150 1975);
DISPLAY INVISIBLE (-5150 1975);
FORCEPROP 1 LAST OFFPAGE TRUE
J 2
(-5475 1850);
DISPLAY 1.170213 (-5475 1850);
PAINT GREEN (-5475 1850);
DISPLAY INVISIBLE (-5475 1850);
FORCEPROP 1 LAST COMMENT_BODY TRUE
J 2
(-5275 1875);
DISPLAY 1.170213 (-5275 1875);
PAINT GREEN (-5275 1875);
DISPLAY INVISIBLE (-5275 1875);
FORCEPROP 2 LAST PATH I5
J 0
(-4950 2100);
DISPLAY 1.021277 (-4950 2100);
PAINT ORANGE (-4950 2100);
DISPLAY INVISIBLE (-4950 2100);
FORCEADD OFFPAGE..1
(-4750 3450);
FORCEPROP 2 LAST $XR0 73 
J 0
(-5001 3450);
DISPLAY 0.638298 (-5001 3450);
PAINT MONO (-5001 3450);
FORCEPROP 2 LAST CDS_LIB mstr_standard
J 0
(-4750 3450);
PAINT MONO (-4750 3450);
DISPLAY INVISIBLE (-4750 3450);
FORCEPROP 1 LAST OFFPAGE TRUE
J 0
(-4425 3325);
DISPLAY 1.170213 (-4425 3325);
PAINT GREEN (-4425 3325);
DISPLAY INVISIBLE (-4425 3325);
FORCEPROP 1 LAST COMMENT_BODY TRUE
J 0
(-4625 3350);
DISPLAY 1.170213 (-4625 3350);
PAINT GREEN (-4625 3350);
DISPLAY INVISIBLE (-4625 3350);
FORCEPROP 2 LAST PATH I50
J 0
(-4700 3525);
DISPLAY 1.021277 (-4700 3525);
PAINT ORANGE (-4700 3525);
DISPLAY INVISIBLE (-4700 3525);
FORCEADD GND..1
(-2150 950);
FORCEPROP 3 LASTPIN (-2150 1000) SIG_NAME GND\g
J 0
(-2140 1010);
DISPLAY 0.659574 (-2140 1010);
PAINT MONO (-2140 1010);
DISPLAY INVISIBLE (-2140 1010);
FORCEPROP 1 LAST VOLTAGE 0.0V
J 0
(-2195 907);
DISPLAY 0.340426 (-2195 907);
PAINT SKYBLUE (-2195 907);
DISPLAY INVISIBLE (-2195 907);
FORCEPROP 2 LAST CDS_LIB mstr_symbols
J 0
(-2150 950);
PAINT MONO (-2150 950);
DISPLAY INVISIBLE (-2150 950);
FORCEPROP 1 LAST SIZE 1B
J 0
(-2075 900);
DISPLAY 1.404255 (-2075 900);
PAINT AQUA (-2075 900);
DISPLAY INVISIBLE (-2075 900);
FORCEPROP 1 LAST BODY_TYPE PLUMBING
J 0
(-2195 907);
DISPLAY 0.340426 (-2195 907);
PAINT GREEN (-2195 907);
DISPLAY INVISIBLE (-2195 907);
FORCEPROP 1 LAST PATH I56
J 0
(-2075 950);
DISPLAY 0.872340 (-2075 950);
PAINT AQUA (-2075 950);
DISPLAY INVISIBLE (-2075 950);
FORCEPROP 1 LAST HDL_POWER GND
J 0
(-2150 1100);
PAINT GREEN (-2150 1100);
DISPLAY INVISIBLE (-2150 1100);
FORCEADD GND..1
(-3975 925);
FORCEPROP 3 LASTPIN (-3975 975) SIG_NAME GND\g
J 0
(-3965 985);
DISPLAY 0.659574 (-3965 985);
PAINT MONO (-3965 985);
DISPLAY INVISIBLE (-3965 985);
FORCEPROP 1 LAST VOLTAGE 0.0V
J 0
(-4020 882);
DISPLAY 0.340426 (-4020 882);
PAINT SKYBLUE (-4020 882);
DISPLAY INVISIBLE (-4020 882);
FORCEPROP 1 LAST SIZE 1B
J 0
(-3900 875);
DISPLAY 1.404255 (-3900 875);
PAINT AQUA (-3900 875);
DISPLAY INVISIBLE (-3900 875);
FORCEPROP 2 LAST CDS_LIB mstr_symbols
J 0
(-3975 925);
PAINT MONO (-3975 925);
DISPLAY INVISIBLE (-3975 925);
FORCEPROP 1 LAST BODY_TYPE PLUMBING
J 0
(-4020 882);
DISPLAY 0.340426 (-4020 882);
PAINT GREEN (-4020 882);
DISPLAY INVISIBLE (-4020 882);
FORCEPROP 1 LAST PATH I60
J 0
(-3900 925);
DISPLAY 0.872340 (-3900 925);
PAINT AQUA (-3900 925);
DISPLAY INVISIBLE (-3900 925);
FORCEPROP 1 LAST HDL_POWER GND
J 0
(-3975 1075);
PAINT GREEN (-3975 1075);
DISPLAY INVISIBLE (-3975 1075);
FORCEADD CAPP..1
(-1675 2975);
FORCEPROP 1 LAST LOCATION C4E24
J 0
(-1625 3075);
DISPLAY 0.617021 (-1625 3075);
PAINT AQUA (-1625 3075);
FORCEPROP 1 LAST PART_NUMBER 699013-049
J 0
(-1625 2775);
DISPLAY 0.617021 (-1625 2775);
PAINT BLUE (-1625 2775);
FORCEPROP 1 LAST VALUE 470UF
J 0
(-1625 3025);
DISPLAY 0.617021 (-1625 3025);
PAINT SKYBLUE (-1625 3025);
FORCEPROP 1 LAST TOLERANCE 20%
J 0
(-1625 2975);
DISPLAY 0.617021 (-1625 2975);
PAINT SKYBLUE (-1625 2975);
FORCEPROP 1 LAST PACK_TYPE 3018
J 0
(-1625 2825);
DISPLAY 0.617021 (-1625 2825);
PAINT SKYBLUE (-1625 2825);
FORCEPROP 1 LAST MATERIAL ALUM
J 0
(-1625 2875);
DISPLAY 0.617021 (-1625 2875);
PAINT SKYBLUE (-1625 2875);
FORCEPROP 1 LASTPIN (-1675 2875) $PN 2
J 0
(-1665 2860);
DISPLAY 0.617021 (-1665 2860);
PAINT WHITE (-1665 2860);
FORCEPROP 1 LASTPIN (-1675 3075) $PN 1
J 0
(-1665 3060);
DISPLAY 0.617021 (-1665 3060);
PAINT WHITE (-1665 3060);
FORCEPROP 1 LAST VOLTAGE 2.5V
J 0
(-1625 2925);
DISPLAY 1.617021 (-1625 2925);
PAINT SKYBLUE (-1625 2925);
DISPLAY INVISIBLE (-1625 2925);
FORCEPROP 2 LAST CDS_LIB mstr_discrete
J 0
(-1675 2975);
DISPLAY 1.617021 (-1675 2975);
PAINT ORANGE (-1675 2975);
DISPLAY INVISIBLE (-1675 2975);
FORCEPROP 2 LAST BOM_COST PVMCP_MCP_CPU1_VR
J 0
(-1625 3125);
DISPLAY 1.617021 (-1625 3125);
PAINT WHITE (-1625 3125);
DISPLAY INVISIBLE (-1625 3125);
FORCEPROP 2 LAST CDS_SEC 1
J 0
(-1625 3175);
DISPLAY 1.617021 (-1625 3175);
PAINT MONO (-1625 3175);
DISPLAY INVISIBLE (-1625 3175);
FORCEPROP 2 LAST $SEC 1
J 0
(-1625 3175);
DISPLAY 1.617021 (-1625 3175);
PAINT MONO (-1625 3175);
DISPLAY INVISIBLE (-1625 3175);
FORCEPROP 2 LAST CDS_LOCATION C4E24
J 0
(-1625 3075);
DISPLAY 0.617021 (-1625 3075);
PAINT AQUA (-1625 3075);
DISPLAY INVISIBLE (-1625 3075);
FORCEPROP 1 LAST PATH I61
J 0
(-1625 3125);
DISPLAY 0.978723 (-1625 3125);
PAINT ORANGE (-1625 3125);
DISPLAY INVISIBLE (-1625 3125);
FORCEPROP 2 LAST ROOM PVMCP_MCP_CPU1_VR
J 0
(-1625 3100);
DISPLAY 1.617021 (-1625 3100);
PAINT WHITE (-1625 3100);
DISPLAY INVISIBLE (-1625 3100);
FORCEADD CAPP..1
(-1400 2975);
FORCEPROP 1 LAST LOCATION C6R16
J 0
(-1350 3075);
DISPLAY 0.617021 (-1350 3075);
PAINT AQUA (-1350 3075);
FORCEPROP 1 LAST PART_NUMBER 699013-049
J 0
(-1325 2775);
DISPLAY 0.617021 (-1325 2775);
PAINT BLUE (-1325 2775);
FORCEPROP 1 LAST VALUE 470UF
J 0
(-1350 3025);
DISPLAY 0.617021 (-1350 3025);
PAINT SKYBLUE (-1350 3025);
FORCEPROP 1 LAST TOLERANCE 20%
J 0
(-1350 2975);
DISPLAY 0.617021 (-1350 2975);
PAINT SKYBLUE (-1350 2975);
FORCEPROP 1 LAST PACK_TYPE 3018
J 0
(-1350 2825);
DISPLAY 0.617021 (-1350 2825);
PAINT SKYBLUE (-1350 2825);
FORCEPROP 1 LAST MATERIAL ALUM
J 0
(-1350 2875);
DISPLAY 0.617021 (-1350 2875);
PAINT SKYBLUE (-1350 2875);
FORCEPROP 1 LASTPIN (-1400 2875) $PN 2
J 0
(-1390 2860);
DISPLAY 0.617021 (-1390 2860);
PAINT WHITE (-1390 2860);
FORCEPROP 1 LASTPIN (-1400 3075) $PN 1
J 0
(-1390 3060);
DISPLAY 0.617021 (-1390 3060);
PAINT WHITE (-1390 3060);
FORCEPROP 1 LAST VOLTAGE 2.5V
J 0
(-1350 2925);
DISPLAY 1.617021 (-1350 2925);
PAINT SKYBLUE (-1350 2925);
DISPLAY INVISIBLE (-1350 2925);
FORCEPROP 2 LAST SEC_TYPE 3018
J 0
(-1345 3195);
DISPLAY 1.659574 (-1345 3195);
PAINT ORANGE (-1345 3195);
DISPLAY INVISIBLE (-1345 3195);
FORCEPROP 2 LAST BOM_COST PVMCP_MCP_CPU1_VR
J 0
(-1350 3125);
DISPLAY 1.617021 (-1350 3125);
PAINT WHITE (-1350 3125);
DISPLAY INVISIBLE (-1350 3125);
FORCEPROP 2 LAST CDS_LIB mstr_discrete
J 0
(-1400 2975);
DISPLAY 1.617021 (-1400 2975);
PAINT ORANGE (-1400 2975);
DISPLAY INVISIBLE (-1400 2975);
FORCEPROP 2 LAST SEC 1
J 0
(-1345 3195);
DISPLAY 1.106383 (-1345 3195);
PAINT MONO (-1345 3195);
DISPLAY INVISIBLE (-1345 3195);
FORCEPROP 2 LAST CDS_LOCATION C6R16
J 0
(-1350 3075);
DISPLAY 0.617021 (-1350 3075);
PAINT AQUA (-1350 3075);
DISPLAY INVISIBLE (-1350 3075);
FORCEPROP 1 LAST PATH I62
J 0
(-1350 3125);
DISPLAY 0.978723 (-1350 3125);
PAINT ORANGE (-1350 3125);
DISPLAY INVISIBLE (-1350 3125);
FORCEPROP 2 LAST ROOM PVMCP_MCP_CPU1_VR
J 0
(-1350 3100);
DISPLAY 1.617021 (-1350 3100);
PAINT WHITE (-1350 3100);
DISPLAY INVISIBLE (-1350 3100);
FORCEADD GND..1
(-1700 1525);
FORCEPROP 3 LASTPIN (-1700 1575) SIG_NAME GND\g
J 0
(-1690 1585);
DISPLAY 0.659574 (-1690 1585);
PAINT MONO (-1690 1585);
DISPLAY INVISIBLE (-1690 1585);
FORCEPROP 1 LAST VOLTAGE 0
J 0
(-1700 1525);
DISPLAY 1.340426 (-1700 1525);
PAINT SKYBLUE (-1700 1525);
DISPLAY INVISIBLE (-1700 1525);
FORCEPROP 2 LAST CDS_LIB mstr_symbols
J 0
(-1700 1525);
PAINT MONO (-1700 1525);
DISPLAY INVISIBLE (-1700 1525);
FORCEPROP 1 LAST SIZE 1B
J 0
(-1625 1475);
DISPLAY 1.191489 (-1625 1475);
PAINT GREEN (-1625 1475);
DISPLAY INVISIBLE (-1625 1475);
FORCEPROP 1 LAST BODY_TYPE PLUMBING
J 0
(-1745 1482);
DISPLAY 0.340426 (-1745 1482);
PAINT GREEN (-1745 1482);
DISPLAY INVISIBLE (-1745 1482);
FORCEPROP 1 LAST PATH I64
J 0
(-1625 1525);
DISPLAY 0.872340 (-1625 1525);
PAINT AQUA (-1625 1525);
DISPLAY INVISIBLE (-1625 1525);
FORCEPROP 1 LAST HDL_POWER GND
J 0
(-1700 1675);
DISPLAY 1.191489 (-1700 1675);
PAINT GREEN (-1700 1675);
DISPLAY INVISIBLE (-1700 1675);
FORCEADD CAP_A..1
R 2
(-775 1850);
FORCEPROP 1 LAST LOCATION C4F1
J 2
(-825 1950);
DISPLAY 0.617021 (-825 1950);
PAINT AQUA (-825 1950);
FORCEPROP 1 LAST PART_NUMBER D97712-004
J 2
(-825 1700);
DISPLAY 0.617021 (-825 1700);
PAINT BLUE (-825 1700);
FORCEPROP 1 LAST VALUE 1.0UF
J 2
(-825 1900);
DISPLAY 0.617021 (-825 1900);
PAINT SKYBLUE (-825 1900);
FORCEPROP 1 LAST TOLERANCE 10%
J 2
(-825 1800);
DISPLAY 0.617021 (-825 1800);
PAINT SKYBLUE (-825 1800);
FORCEPROP 1 LAST PACK_TYPE 0402V
J 2
(-825 1650);
DISPLAY 0.617021 (-825 1650);
PAINT SKYBLUE (-825 1650);
FORCEPROP 1 LAST VOLTAGE 6.3V
J 2
(-825 1850);
DISPLAY 0.617021 (-825 1850);
PAINT SKYBLUE (-825 1850);
FORCEPROP 1 LAST MATERIAL X6S
J 2
(-825 1750);
DISPLAY 0.617021 (-825 1750);
PAINT SKYBLUE (-825 1750);
FORCEPROP 1 LASTPIN (-775 1950) $PN 1
J 2
(-785 1930);
DISPLAY 0.617021 (-785 1930);
PAINT ORANGE (-785 1930);
FORCEPROP 1 LASTPIN (-775 1750) $PN 2
J 2
(-785 1730);
DISPLAY 0.617021 (-785 1730);
PAINT ORANGE (-785 1730);
FORCEPROP 2 LAST CDS_LOCATION C4F1
J 2
(-825 1950);
DISPLAY 0.617021 (-825 1950);
PAINT AQUA (-825 1950);
DISPLAY INVISIBLE (-825 1950);
FORCEPROP 2 LAST CDS_LIB dev_discrete
J 0
(-775 1850);
PAINT ORANGE (-775 1850);
DISPLAY INVISIBLE (-775 1850);
FORCEPROP 2 LAST CDS_SEC 1
J 0
(-825 2000);
PAINT ORANGE (-825 2000);
DISPLAY INVISIBLE (-825 2000);
FORCEPROP 2 LAST SEC_TYPE 0402V
J 0
(-825 2050);
DISPLAY 1.021277 (-825 2050);
PAINT ORANGE (-825 2050);
DISPLAY INVISIBLE (-825 2050);
FORCEPROP 2 LAST SEC 1
J 0
(-825 2050);
DISPLAY 0.680851 (-825 2050);
PAINT MONO (-825 2050);
DISPLAY INVISIBLE (-825 2050);
FORCEPROP 1 LAST PATH I68
J 2
(-825 2000);
DISPLAY 0.978723 (-825 2000);
PAINT WHITE (-825 2000);
DISPLAY INVISIBLE (-825 2000);
FORCEPROP 2 LAST ROOM P1V8_MCP_CPU1
J 2
(-825 2000);
DISPLAY 1.659574 (-825 2000);
PAINT WHITE (-825 2000);
DISPLAY INVISIBLE (-825 2000);
FORCEADD CAP_A..1
R 2
(-1225 1850);
FORCEPROP 1 LAST LOCATION C4F3
J 2
(-1275 1950);
DISPLAY 0.617021 (-1275 1950);
PAINT AQUA (-1275 1950);
FORCEPROP 1 LAST PART_NUMBER D97712-004
J 2
(-1275 1700);
DISPLAY 0.617021 (-1275 1700);
PAINT BLUE (-1275 1700);
FORCEPROP 1 LAST VALUE 1.0UF
J 2
(-1275 1900);
DISPLAY 0.617021 (-1275 1900);
PAINT SKYBLUE (-1275 1900);
FORCEPROP 1 LAST TOLERANCE 10%
J 2
(-1275 1800);
DISPLAY 0.617021 (-1275 1800);
PAINT SKYBLUE (-1275 1800);
FORCEPROP 1 LAST PACK_TYPE 0402V
J 2
(-1275 1650);
DISPLAY 0.617021 (-1275 1650);
PAINT SKYBLUE (-1275 1650);
FORCEPROP 1 LAST VOLTAGE 6.3V
J 2
(-1275 1850);
DISPLAY 0.617021 (-1275 1850);
PAINT SKYBLUE (-1275 1850);
FORCEPROP 1 LAST MATERIAL X6S
J 2
(-1275 1750);
DISPLAY 0.617021 (-1275 1750);
PAINT SKYBLUE (-1275 1750);
FORCEPROP 1 LASTPIN (-1225 1950) $PN 1
J 2
(-1235 1930);
DISPLAY 0.617021 (-1235 1930);
PAINT ORANGE (-1235 1930);
FORCEPROP 1 LASTPIN (-1225 1750) $PN 2
J 2
(-1235 1730);
DISPLAY 0.617021 (-1235 1730);
PAINT ORANGE (-1235 1730);
FORCEPROP 2 LAST CDS_LOCATION C4F3
J 2
(-1275 1950);
DISPLAY 0.617021 (-1275 1950);
PAINT AQUA (-1275 1950);
DISPLAY INVISIBLE (-1275 1950);
FORCEPROP 2 LAST CDS_LIB dev_discrete
J 0
(-1225 1850);
PAINT ORANGE (-1225 1850);
DISPLAY INVISIBLE (-1225 1850);
FORCEPROP 2 LAST CDS_SEC 1
J 0
(-1275 2000);
PAINT ORANGE (-1275 2000);
DISPLAY INVISIBLE (-1275 2000);
FORCEPROP 2 LAST SEC_TYPE 0402V
J 0
(-1275 2050);
DISPLAY 1.021277 (-1275 2050);
PAINT ORANGE (-1275 2050);
DISPLAY INVISIBLE (-1275 2050);
FORCEPROP 2 LAST SEC 1
J 0
(-1275 2050);
DISPLAY 0.680851 (-1275 2050);
PAINT MONO (-1275 2050);
DISPLAY INVISIBLE (-1275 2050);
FORCEPROP 1 LAST PATH I70
J 2
(-1275 2000);
DISPLAY 0.978723 (-1275 2000);
PAINT WHITE (-1275 2000);
DISPLAY INVISIBLE (-1275 2000);
FORCEPROP 2 LAST ROOM P1V8_MCP_CPU1
J 2
(-1275 2000);
DISPLAY 1.659574 (-1275 2000);
PAINT WHITE (-1275 2000);
DISPLAY INVISIBLE (-1275 2000);
FORCEADD GND..1
(-1225 1500);
FORCEPROP 3 LASTPIN (-1225 1550) SIG_NAME GND\g
J 0
(-1215 1560);
DISPLAY 0.659574 (-1215 1560);
PAINT MONO (-1215 1560);
DISPLAY INVISIBLE (-1215 1560);
FORCEPROP 1 LAST VOLTAGE 0.0V
J 0
(-1270 1457);
DISPLAY 0.340426 (-1270 1457);
PAINT SKYBLUE (-1270 1457);
DISPLAY INVISIBLE (-1270 1457);
FORCEPROP 1 LAST SIZE 1B
J 0
(-1150 1450);
DISPLAY 1.404255 (-1150 1450);
PAINT AQUA (-1150 1450);
DISPLAY INVISIBLE (-1150 1450);
FORCEPROP 2 LAST CDS_LIB mstr_symbols
J 0
(-1225 1500);
PAINT ORANGE (-1225 1500);
DISPLAY INVISIBLE (-1225 1500);
FORCEPROP 1 LAST BODY_TYPE PLUMBING
J 0
(-1270 1457);
DISPLAY 0.340426 (-1270 1457);
PAINT GREEN (-1270 1457);
DISPLAY INVISIBLE (-1270 1457);
FORCEPROP 1 LAST PATH I75
J 0
(-1150 1500);
DISPLAY 0.872340 (-1150 1500);
PAINT AQUA (-1150 1500);
DISPLAY INVISIBLE (-1150 1500);
FORCEPROP 1 LAST HDL_POWER GND
J 0
(-1225 1650);
PAINT GREEN (-1225 1650);
DISPLAY INVISIBLE (-1225 1650);
FORCEADD GND..1
(-1525 2675);
FORCEPROP 3 LASTPIN (-1525 2725) SIG_NAME GND\g
J 0
(-1515 2735);
DISPLAY 0.659574 (-1515 2735);
PAINT MONO (-1515 2735);
DISPLAY INVISIBLE (-1515 2735);
FORCEPROP 1 LAST VOLTAGE 0
J 0
(-1525 2675);
PAINT SKYBLUE (-1525 2675);
DISPLAY INVISIBLE (-1525 2675);
FORCEPROP 2 LAST BOM_COST PROC_VRD_VCCIN_CPU0
J 0
(-1900 2750);
DISPLAY 1.446809 (-1900 2750);
PAINT MONO (-1900 2750);
DISPLAY INVISIBLE (-1900 2750);
FORCEPROP 1 LAST SIZE 1B
J 0
(-1450 2625);
DISPLAY 1.723404 (-1450 2625);
PAINT GREEN (-1450 2625);
DISPLAY INVISIBLE (-1450 2625);
FORCEPROP 2 LAST CDS_LIB mstr_symbols
J 0
(-1525 2675);
PAINT MONO (-1525 2675);
DISPLAY INVISIBLE (-1525 2675);
FORCEPROP 1 LAST BODY_TYPE PLUMBING
J 0
(-1570 2632);
DISPLAY 0.340426 (-1570 2632);
PAINT GREEN (-1570 2632);
DISPLAY INVISIBLE (-1570 2632);
FORCEPROP 1 LAST PATH I81
J 0
(-1450 2675);
DISPLAY 0.872340 (-1450 2675);
PAINT AQUA (-1450 2675);
DISPLAY INVISIBLE (-1450 2675);
FORCEPROP 2 LAST ROOM PVSA_CPU0_DECAP_VR
J 0
(-2075 2750);
DISPLAY 1.936170 (-2075 2750);
PAINT ORANGE (-2075 2750);
DISPLAY INVISIBLE (-2075 2750);
FORCEPROP 1 LAST HDL_POWER GND
J 0
(-1525 2825);
DISPLAY 1.723404 (-1525 2825);
PAINT GREEN (-1525 2825);
DISPLAY INVISIBLE (-1525 2825);
FORCEADD OFFPAGE..1
(-7675 1775);
FORCEPROP 2 LAST $XR0 73 
J 0
(-7896 1775);
DISPLAY 0.638298 (-7896 1775);
PAINT MONO (-7896 1775);
FORCEPROP 2 LAST ROOM PVSA_CPU0_VSENSE_VR
J 0
(-8075 1850);
PAINT ORANGE (-8075 1850);
DISPLAY INVISIBLE (-8075 1850);
FORCEPROP 2 LAST CDS_LIB mstr_standard
J 0
(-7675 1775);
PAINT MONO (-7675 1775);
DISPLAY INVISIBLE (-7675 1775);
FORCEPROP 2 LAST BOM_COST PROC_VRD_VCCIN_CPU0
J 0
(-7350 1825);
PAINT MONO (-7350 1825);
DISPLAY INVISIBLE (-7350 1825);
FORCEPROP 1 LAST OFFPAGE TRUE
J 0
(-7350 1650);
DISPLAY 0.872340 (-7350 1650);
PAINT GREEN (-7350 1650);
DISPLAY INVISIBLE (-7350 1650);
FORCEPROP 1 LAST COMMENT_BODY TRUE
J 0
(-7550 1675);
DISPLAY 0.872340 (-7550 1675);
PAINT GREEN (-7550 1675);
DISPLAY INVISIBLE (-7550 1675);
FORCEPROP 2 LAST PATH I83
J 0
(-7500 1850);
DISPLAY 1.021277 (-7500 1850);
PAINT ORANGE (-7500 1850);
DISPLAY INVISIBLE (-7500 1850);
FORCEADD OFFPAGE..1
(-7675 1725);
FORCEPROP 2 LAST $XR0 73 
J 0
(-7896 1725);
DISPLAY 0.638298 (-7896 1725);
PAINT MONO (-7896 1725);
FORCEPROP 2 LAST BOM_COST PROC_VRD_VCCIN_CPU0
J 0
(-7350 1775);
PAINT MONO (-7350 1775);
DISPLAY INVISIBLE (-7350 1775);
FORCEPROP 2 LAST ROOM PVSA_CPU0_VSENSE_VR
J 0
(-8075 1800);
PAINT ORANGE (-8075 1800);
DISPLAY INVISIBLE (-8075 1800);
FORCEPROP 2 LAST CDS_LIB mstr_standard
J 0
(-7675 1725);
PAINT MONO (-7675 1725);
DISPLAY INVISIBLE (-7675 1725);
FORCEPROP 1 LAST OFFPAGE TRUE
J 0
(-7350 1600);
DISPLAY 0.872340 (-7350 1600);
PAINT GREEN (-7350 1600);
DISPLAY INVISIBLE (-7350 1600);
FORCEPROP 1 LAST COMMENT_BODY TRUE
J 0
(-7550 1625);
DISPLAY 0.872340 (-7550 1625);
PAINT GREEN (-7550 1625);
DISPLAY INVISIBLE (-7550 1625);
FORCEPROP 2 LAST PATH I84
J 0
(-7625 1800);
DISPLAY 1.021277 (-7625 1800);
PAINT ORANGE (-7625 1800);
DISPLAY INVISIBLE (-7625 1800);
FORCEADD GND..1
(-7150 1875);
FORCEPROP 3 LASTPIN (-7150 1925) SIG_NAME GND\g
J 0
(-7140 1935);
DISPLAY 0.659574 (-7140 1935);
PAINT MONO (-7140 1935);
DISPLAY INVISIBLE (-7140 1935);
FORCEPROP 1 LAST VOLTAGE 0.0V
J 0
(-7195 1832);
DISPLAY 0.340426 (-7195 1832);
PAINT SKYBLUE (-7195 1832);
DISPLAY INVISIBLE (-7195 1832);
FORCEPROP 2 LAST CDS_LIB mstr_symbols
J 0
(-7150 1875);
PAINT MONO (-7150 1875);
DISPLAY INVISIBLE (-7150 1875);
FORCEPROP 1 LAST SIZE 1B
J 0
(-7075 1825);
DISPLAY 1.404255 (-7075 1825);
PAINT AQUA (-7075 1825);
DISPLAY INVISIBLE (-7075 1825);
FORCEPROP 1 LAST BODY_TYPE PLUMBING
J 0
(-7195 1832);
DISPLAY 0.340426 (-7195 1832);
PAINT GREEN (-7195 1832);
DISPLAY INVISIBLE (-7195 1832);
FORCEPROP 1 LAST PATH I85
J 0
(-7075 1875);
DISPLAY 0.872340 (-7075 1875);
PAINT AQUA (-7075 1875);
DISPLAY INVISIBLE (-7075 1875);
FORCEPROP 1 LAST HDL_POWER GND
J 0
(-7150 2025);
PAINT GREEN (-7150 2025);
DISPLAY INVISIBLE (-7150 2025);
FORCEADD P12V_STBY..1
(-6950 4750);
FORCEPROP 3 LASTPIN (-6950 4700) SIG_NAME P12V_STBY\g
J 0
(-6940 4710);
DISPLAY 0.659574 (-6940 4710);
PAINT MONO (-6940 4710);
DISPLAY INVISIBLE (-6940 4710);
FORCEPROP 1 LAST VOLTAGE 12.0V
J 0
(-6995 4707);
DISPLAY 0.340426 (-6995 4707);
PAINT SKYBLUE (-6995 4707);
DISPLAY INVISIBLE (-6995 4707);
FORCEPROP 2 LAST CDS_LIB mstr_symbols
J 0
(-6950 4750);
PAINT MONO (-6950 4750);
DISPLAY INVISIBLE (-6950 4750);
FORCEPROP 1 LAST SIZE 1B
J 0
(-6905 4772);
DISPLAY 0.340426 (-6905 4772);
PAINT GREEN (-6905 4772);
DISPLAY INVISIBLE (-6905 4772);
FORCEPROP 1 LAST BODY_TYPE PLUMBING
J 0
(-6995 4707);
DISPLAY 0.340426 (-6995 4707);
PAINT GREEN (-6995 4707);
DISPLAY INVISIBLE (-6995 4707);
FORCEPROP 1 LAST PATH I86
J 0
(-6905 4752);
DISPLAY 0.340426 (-6905 4752);
PAINT GREEN (-6905 4752);
DISPLAY INVISIBLE (-6905 4752);
FORCEPROP 1 LAST HDL_POWER P12V_STBY
J 0
(-7250 4625);
DISPLAY 0.872340 (-7250 4625);
PAINT ORANGE (-7250 4625);
DISPLAY INVISIBLE (-7250 4625);
FORCEADD P3V3_STBY..1
(-5525 4525);
FORCEPROP 3 LASTPIN (-5525 4475) SIG_NAME P3V3_STBY\g
J 0
(-5515 4485);
DISPLAY 0.659574 (-5515 4485);
PAINT MONO (-5515 4485);
DISPLAY INVISIBLE (-5515 4485);
FORCEPROP 1 LAST VOLTAGE +3.3V
J 0
(-5325 4675);
DISPLAY 1.021277 (-5325 4675);
PAINT SKYBLUE (-5325 4675);
DISPLAY INVISIBLE (-5325 4675);
FORCEPROP 2 LAST CDS_LIB mstr_symbols
J 0
(-5525 4525);
PAINT MONO (-5525 4525);
DISPLAY INVISIBLE (-5525 4525);
FORCEPROP 1 LAST SIZE 1B
J 0
(-5480 4547);
DISPLAY 0.340426 (-5480 4547);
PAINT GREEN (-5480 4547);
DISPLAY INVISIBLE (-5480 4547);
FORCEPROP 1 LAST BODY_TYPE PLUMBING
J 0
(-5570 4482);
DISPLAY 0.340426 (-5570 4482);
PAINT GREEN (-5570 4482);
DISPLAY INVISIBLE (-5570 4482);
FORCEPROP 1 LAST PATH I87
J 0
(-5480 4527);
DISPLAY 0.340426 (-5480 4527);
PAINT GREEN (-5480 4527);
DISPLAY INVISIBLE (-5480 4527);
FORCEPROP 1 LAST HDL_POWER P3V3_STBY
J 0
(-5825 4400);
DISPLAY 0.872340 (-5825 4400);
PAINT ORANGE (-5825 4400);
DISPLAY INVISIBLE (-5825 4400);
FORCEADD P5V_STBY..1
(-5500 3850);
FORCEPROP 3 LASTPIN (-5500 3800) SIG_NAME P5V_STBY\g
J 0
(-5490 3810);
DISPLAY 0.659574 (-5490 3810);
PAINT MONO (-5490 3810);
DISPLAY INVISIBLE (-5490 3810);
FORCEPROP 1 LAST VOLTAGE +5.0V
J 0
(-5300 4000);
DISPLAY 1.021277 (-5300 4000);
PAINT SKYBLUE (-5300 4000);
DISPLAY INVISIBLE (-5300 4000);
FORCEPROP 2 LAST CDS_LIB mstr_symbols
J 0
(-5500 3850);
PAINT MONO (-5500 3850);
DISPLAY INVISIBLE (-5500 3850);
FORCEPROP 1 LAST SIZE 1B
J 0
(-5455 3872);
DISPLAY 0.340426 (-5455 3872);
PAINT GREEN (-5455 3872);
DISPLAY INVISIBLE (-5455 3872);
FORCEPROP 1 LAST BODY_TYPE PLUMBING
J 0
(-5545 3807);
DISPLAY 0.340426 (-5545 3807);
PAINT GREEN (-5545 3807);
DISPLAY INVISIBLE (-5545 3807);
FORCEPROP 1 LAST PATH I88
J 0
(-5455 3852);
DISPLAY 0.340426 (-5455 3852);
PAINT GREEN (-5455 3852);
DISPLAY INVISIBLE (-5455 3852);
FORCEPROP 1 LAST HDL_POWER P5V_STBY
J 0
(-5800 3725);
DISPLAY 0.872340 (-5800 3725);
PAINT ORANGE (-5800 3725);
DISPLAY INVISIBLE (-5800 3725);
FORCEADD OFFPAGE..4
(-5100 1275);
FORCEPROP 2 LAST $XR0 55 
J 0
(-4914 1275);
DISPLAY 0.638298 (-4914 1275);
PAINT MONO (-4914 1275);
FORCEPROP 2 LAST $XR1 206 
J 0
(-4824 1275);
DISPLAY 0.638298 (-4824 1275);
PAINT MONO (-4824 1275);
FORCEPROP 2 LAST $XR2 213 
J 0
(-4704 1275);
DISPLAY 0.638298 (-4704 1275);
PAINT MONO (-4704 1275);
FORCEPROP 2 LAST CDS_LIB mstr_standard
J 0
(-5100 1275);
PAINT MONO (-5100 1275);
DISPLAY INVISIBLE (-5100 1275);
FORCEPROP 2 LAST ROOM P0V95_FPGA_CPU0_VR
J 0
(-5650 1350);
DISPLAY 1.361702 (-5650 1350);
PAINT ORANGE (-5650 1350);
DISPLAY INVISIBLE (-5650 1350);
FORCEPROP 1 LAST OFFPAGE TRUE
J 0
(-4775 1150);
DISPLAY 0.872340 (-4775 1150);
PAINT GREEN (-4775 1150);
DISPLAY INVISIBLE (-4775 1150);
FORCEPROP 1 LAST COMMENT_BODY TRUE
J 0
(-5125 1175);
DISPLAY 0.872340 (-5125 1175);
PAINT GREEN (-5125 1175);
DISPLAY INVISIBLE (-5125 1175);
FORCEPROP 2 LAST PATH I90
J 0
(-5050 1350);
DISPLAY 1.021277 (-5050 1350);
PAINT ORANGE (-5050 1350);
DISPLAY INVISIBLE (-5050 1350);
FORCEADD GND..1
(-5125 2175);
FORCEPROP 3 LASTPIN (-5125 2225) SIG_NAME GND\g
J 0
(-5115 2235);
DISPLAY 0.659574 (-5115 2235);
PAINT MONO (-5115 2235);
DISPLAY INVISIBLE (-5115 2235);
FORCEPROP 1 LAST VOLTAGE 0.0V
J 0
(-5170 2132);
DISPLAY 0.340426 (-5170 2132);
PAINT SKYBLUE (-5170 2132);
DISPLAY INVISIBLE (-5170 2132);
FORCEPROP 2 LAST CDS_LIB mstr_symbols
J 0
(-5125 2175);
PAINT MONO (-5125 2175);
DISPLAY INVISIBLE (-5125 2175);
FORCEPROP 1 LAST SIZE 1B
J 0
(-5050 2125);
DISPLAY 1.404255 (-5050 2125);
PAINT AQUA (-5050 2125);
DISPLAY INVISIBLE (-5050 2125);
FORCEPROP 1 LAST BODY_TYPE PLUMBING
J 0
(-5170 2132);
DISPLAY 0.340426 (-5170 2132);
PAINT GREEN (-5170 2132);
DISPLAY INVISIBLE (-5170 2132);
FORCEPROP 1 LAST PATH I94
J 0
(-5050 2175);
DISPLAY 0.872340 (-5050 2175);
PAINT AQUA (-5050 2175);
DISPLAY INVISIBLE (-5050 2175);
FORCEPROP 1 LAST HDL_POWER GND
J 0
(-5125 2325);
PAINT GREEN (-5125 2325);
DISPLAY INVISIBLE (-5125 2325);
FORCEADD GND..1
(-7125 1425);
FORCEPROP 3 LASTPIN (-7125 1475) SIG_NAME GND\g
J 0
(-7115 1485);
DISPLAY 0.659574 (-7115 1485);
PAINT MONO (-7115 1485);
DISPLAY INVISIBLE (-7115 1485);
FORCEPROP 1 LAST VOLTAGE 0.0V
J 0
(-7170 1382);
DISPLAY 0.340426 (-7170 1382);
PAINT SKYBLUE (-7170 1382);
DISPLAY INVISIBLE (-7170 1382);
FORCEPROP 2 LAST CDS_LIB mstr_symbols
J 0
(-7125 1425);
PAINT MONO (-7125 1425);
DISPLAY INVISIBLE (-7125 1425);
FORCEPROP 1 LAST SIZE 1B
J 0
(-7050 1375);
DISPLAY 1.404255 (-7050 1375);
PAINT AQUA (-7050 1375);
DISPLAY INVISIBLE (-7050 1375);
FORCEPROP 1 LAST BODY_TYPE PLUMBING
J 0
(-7170 1382);
DISPLAY 0.340426 (-7170 1382);
PAINT GREEN (-7170 1382);
DISPLAY INVISIBLE (-7170 1382);
FORCEPROP 1 LAST PATH I95
J 0
(-7050 1425);
DISPLAY 0.872340 (-7050 1425);
PAINT AQUA (-7050 1425);
DISPLAY INVISIBLE (-7050 1425);
FORCEPROP 1 LAST HDL_POWER GND
J 0
(-7125 1575);
PAINT GREEN (-7125 1575);
DISPLAY INVISIBLE (-7125 1575);
FORCEADD DESIGN_NOTE..1
(-7075 650);
PAINT PURPLE (-7075 650);
FORCEPROP 0 LAST L1 SVID ADDRESS: VCCMCP: 0X03, VCCIOMCP 0X04, P1V8MCP 0X05
J 0
(-7275 525);
PAINT VIOLET (-7275 525);
FORCEPROP 2 LAST CDS_LIB mstr_symbols
J 0
(-7075 650);
PAINT MONO (-7075 650);
DISPLAY INVISIBLE (-7075 650);
FORCEPROP 2 LAST BOM_COST SM_CONTROLLER
J 0
(-7275 600);
PAINT MONO (-7275 600);
DISPLAY INVISIBLE (-7275 600);
FORCEPROP 1 LAST COMMENT_BODY TRUE
J 0
(-7050 750);
DISPLAY 1.319149 (-7050 750);
PAINT GREEN (-7050 750);
DISPLAY INVISIBLE (-7050 750);
FORCEPROP 2 LAST ROOM PVCCIN_CPU0_VR
J 0
(-7275 600);
PAINT MONO (-7275 600);
DISPLAY INVISIBLE (-7275 600);
FORCEADD INTEL_CORP_BPAGE..1
(-275 50);
FORCEPROP 1 LAST CDS_CON_LAST_MODIFIED Tue Dec 01 11:52:18 2015
J 0
(-1700 375);
DISPLAY 1.361702 (-1700 375);
PAINT GREEN (-1700 375);
DISPLAY INVISIBLE (-1700 375);
FORCEPROP 1 LAST CUSTOM_TXT_CDS <CURRENT_DESIGN_SHEET> OF <TOTAL_DESIGN_SHEETS>
J 0
(-775 75);
PAINT GREEN (-775 75);
FORCEPROP 1 LAST CUSTOM_TXT_CDS <CON_LAST_MODIFIED>
J 0
(-2200 400);
PAINT GREEN (-2200 400);
FORCEPROP 2 LAST CUSTOM_TXT_CDS <XR_PAGE_TITLE>
J 0
(-8165 5300);
DISPLAY 0.638298 (-8165 5300);
PAINT PINK (-8165 5300);
DISPLAY INVISIBLE (-8165 5300);
FORCEPROP 1 LAST SCH_ADDRESS3 Santa Clara, CA 95052-8119
J 0
(-4250 75);
DISPLAY 0.617021 (-4250 75);
PAINT GREEN (-4250 75);
FORCEPROP 1 LAST SCH_ADDRESS2 P.O. BOX 58119
J 0
(-4250 125);
DISPLAY 0.617021 (-4250 125);
PAINT GREEN (-4250 125);
FORCEPROP 1 LAST SCH_ADDRESS1 2200 Mission College Blvd.
J 0
(-4250 175);
DISPLAY 0.617021 (-4250 175);
PAINT GREEN (-4250 175);
FORCEPROP 1 LAST SCH_TITLE MCP CPU1 VRM
J 0
(-8200 100);
DISPLAY 1.212766 (-8200 100);
PAINT ORANGE (-8200 100);
FORCEPROP 1 LAST SCH_NUMBER H4694802
J 0
(-1575 200);
DISPLAY 1.212766 (-1575 200);
PAINT YELLOW (-1575 200);
FORCEPROP 1 LAST SCH_DEPT BESD
J 1
(-4725 150);
DISPLAY 1.212766 (-4725 150);
PAINT YELLOW (-4725 150);
FORCEPROP 1 LAST SCH_REV 2.420
J 0
(-525 200);
DISPLAY 0.978723 (-525 200);
PAINT YELLOW (-525 200);
FORCEPROP 2 LAST PAGE_BORDER TRUE
J 0
(-8165 5300);
DISPLAY 0.851064 (-8165 5300);
PAINT PINK (-8165 5300);
DISPLAY INVISIBLE (-8165 5300);
FORCEPROP 2 LAST CDS_LIB mstr_symbols
J 0
(-275 50);
DISPLAY 1.361702 (-275 50);
PAINT ORANGE (-275 50);
DISPLAY INVISIBLE (-275 50);
FORCEPROP 1 LAST COMMENT_BODY TRUE
J 0
(-263 62);
DISPLAY 0.617021 (-263 62);
PAINT GREEN (-263 62);
DISPLAY INVISIBLE (-263 62);
FORCEPROP 2 LAST CDS_XR_PAGE_TITLE CR-193 : @BASEBOARD_FAB2_LIB.BASEBOARD_FAB2(SCH_1):PAGE193
J 0
(-8165 5300);
DISPLAY 0.638298 (-8165 5300);
PAINT PINK (-8165 5300);
DISPLAY INVISIBLE (-8165 5300);
WIRE 16 -1 (-3550 3700)(-3725 3700);
WIRE 16 -1 (-3725 3700)(-3725 3750);
WIRE 16 -1 (-3550 3750)(-3725 3750);
WIRE 16 -1 (-3725 3750)(-3725 3800);
WIRE 16 -1 (-3550 3800)(-3725 3800);
WIRE 16 -1 (-3725 3800)(-3725 4050);
WIRE 16 -1 (-3550 4050)(-3725 4050);
WIRE 16 -1 (-3725 4050)(-3725 4100);
WIRE 16 -1 (-3550 4100)(-3725 4100);
WIRE 16 -1 (-3725 4100)(-3725 4150);
WIRE 16 -1 (-3550 4150)(-3725 4150);
WIRE 16 -1 (-3725 4150)(-3725 4400);
WIRE 16 -1 (-3550 4400)(-3725 4400);
WIRE 16 -1 (-3725 4400)(-3725 4450);
WIRE 16 -1 (-3550 4450)(-3725 4450);
WIRE 16 -1 (-3725 4450)(-3725 4500);
WIRE 16 -1 (-3550 4500)(-3725 4500);
WIRE 16 -1 (-3725 4500)(-3800 4500);
WIRE 16 -1 (-3800 4500)(-3800 4650);
WIRE 16 -1 (-3550 3900)(-3850 3900);
WIRE 16 -1 (-3850 3950)(-3850 3900);
WIRE 16 -1 (-3550 3950)(-3850 3950);
WIRE 16 -1 (-3850 3950)(-3850 4250);
WIRE 16 -1 (-3550 4250)(-3850 4250);
WIRE 16 -1 (-3850 4300)(-3850 4250);
WIRE 16 -1 (-3550 4300)(-3850 4300);
WIRE 16 -1 (-3850 4300)(-3850 4525);
WIRE 16 -1 (-3850 4525)(-4050 4525);
WIRE 16 -1 (-4050 4600)(-4050 4525);
WIRE 16 -1 (-5925 1375)(-5250 1375);
WIRE 16 -1 (-5250 1425)(-5250 1375);
WIRE 16 -1 (-5925 1425)(-5250 1425);
WIRE 16 -1 (-5250 1475)(-5250 1425);
WIRE 16 -1 (-5925 1475)(-5250 1475);
WIRE 16 -1 (-5250 1525)(-5250 1475);
WIRE 16 -1 (-5925 1525)(-5250 1525);
WIRE 16 -1 (-5250 1725)(-5250 1525);
WIRE 16 -1 (-5925 1725)(-5250 1725);
WIRE 16 -1 (-5250 1775)(-5250 1725);
WIRE 16 -1 (-5925 1775)(-5250 1775);
WIRE 16 -1 (-5250 1825)(-5250 1775);
WIRE 16 -1 (-5925 1825)(-5250 1825);
WIRE 16 -1 (-5250 1875)(-5250 1825);
WIRE 16 -1 (-5925 1875)(-5250 1875);
WIRE 16 -1 (-5250 1875)(-5250 2075);
WIRE 16 -1 (-5925 2075)(-5250 2075);
WIRE 16 -1 (-5250 2125)(-5250 2075);
WIRE 16 -1 (-5925 2125)(-5250 2125);
WIRE 16 -1 (-5250 2175)(-5250 2125);
WIRE 16 -1 (-5925 2175)(-5250 2175);
WIRE 16 -1 (-5250 2225)(-5250 2175);
WIRE 16 -1 (-5925 2225)(-5250 2225);
WIRE 16 -1 (-5250 2425)(-5250 2225);
WIRE 16 -1 (-5925 2425)(-5250 2425);
WIRE 16 -1 (-5250 2475)(-5250 2425);
WIRE 16 -1 (-5925 2475)(-5250 2475);
WIRE 16 -1 (-5250 2525)(-5250 2475);
WIRE 16 -1 (-5925 2525)(-5250 2525);
WIRE 16 -1 (-5250 2775)(-5250 2525);
WIRE 16 -1 (-5925 2775)(-5250 2775);
WIRE 16 -1 (-5250 2825)(-5250 2775);
WIRE 16 -1 (-5925 2825)(-5250 2825);
WIRE 16 -1 (-5250 2875)(-5250 2825);
WIRE 16 -1 (-5925 2875)(-5250 2875);
WIRE 16 -1 (-5250 3175)(-5250 2875);
WIRE 16 -1 (-7225 4175)(-6725 4175);
WIRE 16 -1 (-7225 4525)(-7225 4175);
WIRE 16 -1 (-2750 1950)(-2300 1950);
WIRE 16 -1 (-2300 1950)(-2300 2000);
WIRE 16 -1 (-2750 2000)(-2300 2000);
WIRE 16 -1 (-2300 2000)(-2300 2050);
WIRE 16 -1 (-2750 2050)(-2300 2050);
WIRE 16 -1 (-2300 2050)(-2300 2300);
WIRE 16 -1 (-2750 2300)(-2300 2300);
WIRE 16 -1 (-2300 2300)(-2300 2350);
WIRE 16 -1 (-2750 2350)(-2300 2350);
WIRE 16 -1 (-2300 2350)(-2300 2400);
WIRE 16 -1 (-2750 2400)(-2300 2400);
WIRE 16 -1 (-2300 2400)(-2300 2650);
WIRE 16 -1 (-2750 2650)(-2300 2650);
WIRE 16 -1 (-2300 2650)(-2300 2700);
WIRE 16 -1 (-2750 2700)(-2300 2700);
WIRE 16 -1 (-2300 2700)(-2300 2750);
WIRE 16 -1 (-2750 2750)(-2300 2750);
WIRE 16 -1 (-2300 2750)(-2300 3000);
WIRE 16 -1 (-2750 3000)(-2300 3000);
WIRE 16 -1 (-2300 3000)(-2300 3050);
WIRE 16 -1 (-2750 3050)(-2300 3050);
WIRE 16 -1 (-2300 3050)(-2300 3100);
WIRE 16 -1 (-2750 3100)(-2300 3100);
WIRE 16 -1 (-2300 3100)(-2300 3350);
WIRE 16 -1 (-2750 3350)(-2300 3350);
WIRE 16 -1 (-2300 3350)(-2300 3400);
WIRE 16 -1 (-2750 3400)(-2300 3400);
WIRE 16 -1 (-2300 3400)(-2300 3450);
WIRE 16 -1 (-2750 3450)(-2300 3450);
WIRE 16 -1 (-2300 3450)(-2300 3700);
WIRE 16 -1 (-2750 3700)(-2300 3700);
WIRE 16 -1 (-2300 3700)(-2300 3750);
WIRE 16 -1 (-2750 3750)(-2300 3750);
WIRE 16 -1 (-2300 3750)(-2300 3800);
WIRE 16 -1 (-2750 3800)(-2300 3800);
WIRE 16 -1 (-2300 3800)(-2300 4050);
WIRE 16 -1 (-2750 4050)(-2300 4050);
WIRE 16 -1 (-2300 4050)(-2300 4100);
WIRE 16 -1 (-2750 4100)(-2300 4100);
WIRE 16 -1 (-2300 4100)(-2300 4150);
WIRE 16 -1 (-2750 4150)(-2300 4150);
WIRE 16 -1 (-2300 4150)(-2300 4400);
WIRE 16 -1 (-2750 4400)(-2300 4400);
WIRE 16 -1 (-2300 4400)(-2300 4450);
WIRE 16 -1 (-2750 4450)(-2300 4450);
WIRE 16 -1 (-2300 4450)(-2300 4500);
WIRE 16 -1 (-2750 4500)(-2300 4500);
WIRE 16 -1 (-2300 4500)(-2300 4550);
WIRE 16 -1 (-3550 1250)(-3725 1250);
WIRE 16 -1 (-3725 1250)(-3725 1300);
WIRE 16 -1 (-3550 1300)(-3725 1300);
WIRE 16 -1 (-3725 1300)(-3725 1350);
WIRE 16 -1 (-3550 1350)(-3725 1350);
WIRE 16 -1 (-3725 1350)(-3725 1600);
WIRE 16 -1 (-3550 1600)(-3725 1600);
WIRE 16 -1 (-3725 1600)(-3725 1650);
WIRE 16 -1 (-3550 1650)(-3725 1650);
WIRE 16 -1 (-3725 1650)(-3725 1700);
WIRE 16 -1 (-3550 1700)(-3725 1700);
WIRE 16 -1 (-3725 1700)(-3725 1950);
WIRE 16 -1 (-3550 1950)(-3725 1950);
WIRE 16 -1 (-3725 1950)(-3725 2000);
WIRE 16 -1 (-3550 2000)(-3725 2000);
WIRE 16 -1 (-3725 2000)(-3725 2050);
WIRE 16 -1 (-3550 2050)(-3725 2050);
WIRE 16 -1 (-3725 2050)(-3725 2300);
WIRE 16 -1 (-3550 2300)(-3725 2300);
WIRE 16 -1 (-3725 2300)(-3725 2350);
WIRE 16 -1 (-3550 2350)(-3725 2350);
WIRE 16 -1 (-3725 2350)(-3725 2400);
WIRE 16 -1 (-3550 2400)(-3725 2400);
WIRE 16 -1 (-3725 2400)(-3725 2650);
WIRE 16 -1 (-3550 2650)(-3725 2650);
WIRE 16 -1 (-3725 2650)(-3725 2700);
WIRE 16 -1 (-3550 2700)(-3725 2700);
WIRE 16 -1 (-3725 2700)(-3725 2750);
WIRE 16 -1 (-3550 2750)(-3725 2750);
WIRE 16 -1 (-3725 2750)(-3725 3000);
WIRE 16 -1 (-3550 3000)(-3725 3000);
WIRE 16 -1 (-3725 3000)(-3725 3050);
WIRE 16 -1 (-3550 3050)(-3725 3050);
WIRE 16 -1 (-3725 3050)(-3725 3100);
WIRE 16 -1 (-3550 3100)(-3725 3100);
WIRE 16 -1 (-3725 3100)(-3725 3350);
WIRE 16 -1 (-3550 3350)(-3725 3350);
WIRE 16 -1 (-5075 3350)(-3725 3350);
WIRE 16 -1 (-5075 3650)(-5075 3350);
WIRE 16 -1 (-1950 1975)(-1950 2050);
WIRE 16 -1 (-1950 2050)(-1700 2050);
WIRE 16 -1 (-1700 2075)(-1700 2050);
WIRE 16 -1 (-1700 2050)(-1700 1975);
WIRE 16 -1 (-775 1950)(-775 2100);
WIRE 16 -1 (-775 2100)(-1225 2100);
WIRE 16 -1 (-1225 1950)(-1225 2100);
WIRE 16 -1 (-1225 2100)(-1225 2200);
WIRE 16 -1 (-700 4325)(-700 4450);
WIRE 16 -1 (-700 4450)(-1150 4450);
WIRE 16 -1 (-1150 4300)(-1150 4450);
WIRE 16 -1 (-1150 4450)(-1150 4550);
WIRE 16 -1 (-1775 4550)(-1775 4375);
WIRE 16 -1 (-1400 3075)(-1400 3175);
WIRE 16 -1 (-1400 3175)(-1550 3175);
FORCEPROP 0 LAST VOLTAGE 1.2V
J 0
(-1450 3225);
DISPLAY 1.021277 (-1450 3225);
PAINT SKYBLUE (-1450 3225);
DISPLAY INVISIBLE (-1450 3225);
WIRE 16 -1 (-1675 3175)(-1550 3175);
WIRE 16 -1 (-1550 3175)(-1550 3225);
WIRE 16 -1 (-1675 3075)(-1675 3175);
WIRE 16 -1 (-7600 650)(-7600 525);
WIRE 16 -1 (-7600 525)(-7750 525);
WIRE 16 -1 (-7950 525)(-7750 525);
WIRE 16 -1 (-7750 525)(-7750 475);
WIRE 16 -1 (-7950 675)(-7950 525);
WIRE 16 -1 (-7325 4275)(-6725 4275);
WIRE 16 -1 (-7325 4450)(-7325 4275);
WIRE 16 -1 (-1775 4175)(-1775 3925);
WIRE 16 -1 (-700 4125)(-700 3975);
WIRE 16 -1 (-700 3975)(-1150 3975);
WIRE 16 -1 (-1150 3975)(-1150 4100);
WIRE 16 -1 (-1150 3900)(-1150 3975);
WIRE 16 -1 (-2750 4350)(-2150 4350);
WIRE 16 -1 (-2150 4350)(-2150 4300);
WIRE 16 -1 (-2750 4300)(-2150 4300);
WIRE 16 -1 (-2150 4300)(-2150 4250);
WIRE 16 -1 (-2750 4250)(-2150 4250);
WIRE 16 -1 (-2150 4250)(-2150 4000);
WIRE 16 -1 (-2750 4000)(-2150 4000);
WIRE 16 -1 (-2150 4000)(-2150 3950);
WIRE 16 -1 (-2750 3950)(-2150 3950);
WIRE 16 -1 (-2150 3950)(-2150 3900);
WIRE 16 -1 (-2750 3900)(-2150 3900);
WIRE 16 -1 (-2150 3900)(-2150 3650);
WIRE 16 -1 (-2750 3650)(-2150 3650);
WIRE 16 -1 (-2150 3650)(-2150 3600);
WIRE 16 -1 (-2750 3600)(-2150 3600);
WIRE 16 -1 (-2150 3600)(-2150 3550);
WIRE 16 -1 (-2750 3550)(-2150 3550);
WIRE 16 -1 (-2150 3550)(-2150 3300);
WIRE 16 -1 (-2750 3300)(-2150 3300);
WIRE 16 -1 (-2150 3300)(-2150 3250);
WIRE 16 -1 (-2750 3250)(-2150 3250);
WIRE 16 -1 (-2150 3250)(-2150 3200);
WIRE 16 -1 (-2750 3200)(-2150 3200);
WIRE 16 -1 (-2150 3200)(-2150 2950);
WIRE 16 -1 (-2750 2950)(-2150 2950);
WIRE 16 -1 (-2150 2950)(-2150 2900);
WIRE 16 -1 (-2750 2900)(-2150 2900);
WIRE 16 -1 (-2150 2900)(-2150 2850);
WIRE 16 -1 (-2750 2850)(-2150 2850);
WIRE 16 -1 (-2150 2850)(-2150 2600);
WIRE 16 -1 (-2750 2600)(-2150 2600);
WIRE 16 -1 (-2150 2600)(-2150 2550);
WIRE 16 -1 (-2750 2550)(-2150 2550);
WIRE 16 -1 (-2150 2550)(-2150 2500);
WIRE 16 -1 (-2750 2500)(-2150 2500);
WIRE 16 -1 (-2150 2500)(-2150 2250);
WIRE 16 -1 (-2750 2250)(-2150 2250);
WIRE 16 -1 (-2150 2250)(-2150 2200);
WIRE 16 -1 (-2750 2200)(-2150 2200);
WIRE 16 -1 (-2150 2200)(-2150 2150);
WIRE 16 -1 (-2750 2150)(-2150 2150);
WIRE 16 -1 (-2150 1900)(-2150 2150);
WIRE 16 -1 (-2750 1900)(-2150 1900);
WIRE 16 -1 (-2150 1900)(-2150 1850);
WIRE 16 -1 (-2750 1850)(-2150 1850);
WIRE 16 -1 (-2150 1850)(-2150 1800);
WIRE 16 -1 (-2750 1800)(-2150 1800);
WIRE 16 -1 (-2150 1800)(-2150 1700);
WIRE 16 -1 (-2750 1700)(-2150 1700);
WIRE 16 -1 (-2150 1700)(-2150 1650);
WIRE 16 -1 (-2750 1650)(-2150 1650);
WIRE 16 -1 (-2150 1650)(-2150 1600);
WIRE 16 -1 (-2750 1600)(-2150 1600);
WIRE 16 -1 (-2150 1600)(-2150 1550);
WIRE 16 -1 (-2750 1550)(-2150 1550);
WIRE 16 -1 (-2150 1550)(-2150 1500);
WIRE 16 -1 (-2750 1500)(-2150 1500);
WIRE 16 -1 (-2150 1500)(-2150 1450);
WIRE 16 -1 (-2750 1450)(-2150 1450);
WIRE 16 -1 (-2150 1450)(-2150 1350);
WIRE 16 -1 (-2750 1350)(-2150 1350);
WIRE 16 -1 (-2150 1350)(-2150 1300);
WIRE 16 -1 (-2750 1300)(-2150 1300);
WIRE 16 -1 (-2150 1300)(-2150 1250);
WIRE 16 -1 (-2750 1250)(-2150 1250);
WIRE 16 -1 (-2150 1250)(-2150 1200);
WIRE 16 -1 (-2750 1200)(-2150 1200);
WIRE 16 -1 (-2150 1200)(-2150 1150);
WIRE 16 -1 (-2750 1150)(-2150 1150);
WIRE 16 -1 (-2150 1150)(-2150 1100);
WIRE 16 -1 (-2750 1100)(-2150 1100);
WIRE 16 -1 (-2150 1100)(-2150 1000);
WIRE 16 -1 (-3550 3650)(-3975 3650);
WIRE 16 -1 (-3975 3650)(-3975 3600);
WIRE 16 -1 (-3550 3600)(-3975 3600);
WIRE 16 -1 (-3975 3600)(-3975 3550);
WIRE 16 -1 (-3550 3550)(-3975 3550);
WIRE 16 -1 (-3975 3550)(-3975 3300);
WIRE 16 -1 (-3550 3300)(-3975 3300);
WIRE 16 -1 (-3975 3300)(-3975 3250);
WIRE 16 -1 (-3550 3250)(-3975 3250);
WIRE 16 -1 (-3975 3250)(-3975 3200);
WIRE 16 -1 (-3550 3200)(-3975 3200);
WIRE 16 -1 (-3975 3200)(-3975 2950);
WIRE 16 -1 (-3550 2950)(-3975 2950);
WIRE 16 -1 (-3975 2600)(-3975 2950);
WIRE 16 -1 (-3550 2600)(-3975 2600);
WIRE 16 -1 (-3975 2600)(-3975 2550);
WIRE 16 -1 (-3550 2550)(-3975 2550);
WIRE 16 -1 (-3975 2550)(-3975 2500);
WIRE 16 -1 (-3550 2500)(-3975 2500);
WIRE 16 -1 (-3975 2500)(-3975 2250);
WIRE 16 -1 (-3550 2250)(-3975 2250);
WIRE 16 -1 (-3975 2250)(-3975 2200);
WIRE 16 -1 (-3550 2200)(-3975 2200);
WIRE 16 -1 (-3975 2200)(-3975 2150);
WIRE 16 -1 (-3550 2150)(-3975 2150);
WIRE 16 -1 (-3975 2150)(-3975 1900);
WIRE 16 -1 (-3550 1900)(-3975 1900);
WIRE 16 -1 (-3975 1900)(-3975 1850);
WIRE 16 -1 (-3550 1850)(-3975 1850);
WIRE 16 -1 (-3975 1850)(-3975 1800);
WIRE 16 -1 (-3550 1800)(-3975 1800);
WIRE 16 -1 (-3975 1800)(-3975 1550);
WIRE 16 -1 (-3550 1550)(-3975 1550);
WIRE 16 -1 (-3975 1550)(-3975 1500);
WIRE 16 -1 (-3550 1500)(-3975 1500);
WIRE 16 -1 (-3975 1500)(-3975 1450);
WIRE 16 -1 (-3550 1450)(-3975 1450);
WIRE 16 -1 (-3975 1450)(-3975 1200);
WIRE 16 -1 (-3550 1200)(-3975 1200);
WIRE 16 -1 (-3975 1200)(-3975 1150);
WIRE 16 -1 (-3550 1150)(-3975 1150);
WIRE 16 -1 (-3975 1150)(-3975 1100);
WIRE 16 -1 (-3550 1100)(-3975 1100);
WIRE 16 -1 (-3975 1100)(-3975 975);
WIRE 16 -1 (-1950 1775)(-1950 1650);
WIRE 16 -1 (-1950 1650)(-1700 1650);
WIRE 16 -1 (-1700 1775)(-1700 1650);
WIRE 16 -1 (-1700 1650)(-1700 1575);
WIRE 16 -1 (-775 1750)(-775 1625);
WIRE 16 -1 (-775 1625)(-1225 1625);
WIRE 16 -1 (-1225 1750)(-1225 1625);
WIRE 16 -1 (-1225 1625)(-1225 1550);
WIRE 16 -1 (-1400 2875)(-1400 2750);
WIRE 16 -1 (-1400 2750)(-1525 2750);
WIRE 16 -1 (-1675 2750)(-1525 2750);
WIRE 16 -1 (-1525 2725)(-1525 2750);
WIRE 16 -1 (-1675 2750)(-1675 2875);
WIRE 16 -1 (-6725 4325)(-7150 4325);
WIRE 16 -1 (-7150 3975)(-7150 4325);
WIRE 16 -1 (-6725 3975)(-7150 3975);
WIRE 16 -1 (-7150 3975)(-7150 3925);
WIRE 16 -1 (-6725 3925)(-7150 3925);
WIRE 16 -1 (-7150 3925)(-7150 3875);
WIRE 16 -1 (-6725 3875)(-7150 3875);
WIRE 16 -1 (-7150 3875)(-7150 3825);
WIRE 16 -1 (-6725 3825)(-7150 3825);
WIRE 16 -1 (-7150 3825)(-7150 3625);
WIRE 16 -1 (-6725 3625)(-7150 3625);
WIRE 16 -1 (-7150 3625)(-7150 3575);
WIRE 16 -1 (-6725 3575)(-7150 3575);
WIRE 16 -1 (-7150 3575)(-7150 3525);
WIRE 16 -1 (-6725 3525)(-7150 3525);
WIRE 16 -1 (-7150 3525)(-7150 3475);
WIRE 16 -1 (-6725 3475)(-7150 3475);
WIRE 16 -1 (-7150 3475)(-7150 3275);
WIRE 16 -1 (-6725 3275)(-7150 3275);
WIRE 16 -1 (-7150 3275)(-7150 3225);
WIRE 16 -1 (-6725 3225)(-7150 3225);
WIRE 16 -1 (-7150 3225)(-7150 3175);
WIRE 16 -1 (-6725 3175)(-7150 3175);
WIRE 16 -1 (-7150 3175)(-7150 3125);
WIRE 16 -1 (-6725 3125)(-7150 3125);
WIRE 16 -1 (-7150 3125)(-7150 2925);
WIRE 16 -1 (-6725 2925)(-7150 2925);
WIRE 16 -1 (-7150 2925)(-7150 2875);
WIRE 16 -1 (-6725 2875)(-7150 2875);
WIRE 16 -1 (-7150 2875)(-7150 2825);
WIRE 16 -1 (-6725 2825)(-7150 2825);
WIRE 16 -1 (-7150 2825)(-7150 2775);
WIRE 16 -1 (-6725 2775)(-7150 2775);
WIRE 16 -1 (-7150 2775)(-7150 2575);
WIRE 16 -1 (-6725 2575)(-7150 2575);
WIRE 16 -1 (-7150 2575)(-7150 2525);
WIRE 16 -1 (-6725 2525)(-7150 2525);
WIRE 16 -1 (-7150 2525)(-7150 2475);
WIRE 16 -1 (-6725 2475)(-7150 2475);
WIRE 16 -1 (-7150 2475)(-7150 2425);
WIRE 16 -1 (-6725 2425)(-7150 2425);
WIRE 16 -1 (-7150 2425)(-7150 2225);
WIRE 16 -1 (-6725 2225)(-7150 2225);
WIRE 16 -1 (-7150 2225)(-7150 2175);
WIRE 16 -1 (-6725 2175)(-7150 2175);
WIRE 16 -1 (-7150 2125)(-7150 2175);
WIRE 16 -1 (-6725 2125)(-7150 2125);
WIRE 16 -1 (-7150 2075)(-7150 2125);
WIRE 16 -1 (-6725 2075)(-7150 2075);
WIRE 16 -1 (-7150 1925)(-7150 2075);
WIRE 16 -1 (-6950 1925)(-6725 1925);
WIRE 16 -1 (-6950 1975)(-6950 1925);
WIRE 16 -1 (-6950 2275)(-6950 1975);
WIRE 16 -1 (-6950 1975)(-6725 1975);
WIRE 16 -1 (-6725 2275)(-6950 2275);
WIRE 16 -1 (-6950 2275)(-6950 2325);
WIRE 16 -1 (-6725 2325)(-6950 2325);
WIRE 16 -1 (-6950 2325)(-6950 2625);
WIRE 16 -1 (-6725 2625)(-6950 2625);
WIRE 16 -1 (-6950 2625)(-6950 2675);
WIRE 16 -1 (-6725 2675)(-6950 2675);
WIRE 16 -1 (-6950 2675)(-6950 2975);
WIRE 16 -1 (-6725 2975)(-6950 2975);
WIRE 16 -1 (-6950 2975)(-6950 3025);
WIRE 16 -1 (-6725 3025)(-6950 3025);
WIRE 16 -1 (-6950 3025)(-6950 3325);
WIRE 16 -1 (-6725 3325)(-6950 3325);
WIRE 16 -1 (-6950 3325)(-6950 3375);
WIRE 16 -1 (-6725 3375)(-6950 3375);
WIRE 16 -1 (-6950 3375)(-6950 3675);
WIRE 16 -1 (-6725 3675)(-6950 3675);
WIRE 16 -1 (-6950 3675)(-6950 3725);
WIRE 16 -1 (-6725 3725)(-6950 3725);
WIRE 16 -1 (-6950 3725)(-6950 4025);
WIRE 16 -1 (-6725 4025)(-6950 4025);
WIRE 16 -1 (-6950 4025)(-6950 4075);
WIRE 16 -1 (-6725 4075)(-6950 4075);
WIRE 16 -1 (-6950 4075)(-6950 4375);
WIRE 16 -1 (-6725 4375)(-6950 4375);
WIRE 16 -1 (-6950 4375)(-6950 4425);
WIRE 16 -1 (-6725 4425)(-6950 4425);
WIRE 16 -1 (-6950 4425)(-6950 4700);
WIRE 16 -1 (-5925 4325)(-5525 4325);
WIRE 16 -1 (-5525 4325)(-5525 4375);
WIRE 16 -1 (-5925 4375)(-5525 4375);
WIRE 16 -1 (-5525 4375)(-5525 4425);
WIRE 16 -1 (-5925 4425)(-5525 4425);
WIRE 16 -1 (-5525 4425)(-5525 4475);
WIRE 16 -1 (-5925 3625)(-5500 3625);
WIRE 16 -1 (-5500 3625)(-5500 3675);
WIRE 16 -1 (-5925 3675)(-5500 3675);
WIRE 16 -1 (-5500 3675)(-5500 3725);
WIRE 16 -1 (-5925 3725)(-5500 3725);
WIRE 16 -1 (-5500 3725)(-5500 3800);
WIRE 16 -1 (-5925 4275)(-5775 4275);
WIRE 16 -1 (-5775 4225)(-5775 4275);
WIRE 16 -1 (-5925 4225)(-5775 4225);
WIRE 16 -1 (-5775 4225)(-5775 4175);
WIRE 16 -1 (-5925 4175)(-5775 4175);
WIRE 16 -1 (-5775 4175)(-5775 4075);
WIRE 16 -1 (-5925 4075)(-5775 4075);
WIRE 16 -1 (-5775 4075)(-5775 4025);
WIRE 16 -1 (-5925 4025)(-5775 4025);
WIRE 16 -1 (-5775 4025)(-5775 3975);
WIRE 16 -1 (-5925 3975)(-5775 3975);
WIRE 16 -1 (-5775 3975)(-5775 3925);
WIRE 16 -1 (-5925 3925)(-5775 3925);
WIRE 16 -1 (-5775 3925)(-5775 3875);
WIRE 16 -1 (-5925 3875)(-5775 3875);
WIRE 16 -1 (-5775 3875)(-5775 3825);
WIRE 16 -1 (-5925 3825)(-5775 3825);
WIRE 16 -1 (-5775 3575)(-5775 3825);
WIRE 16 -1 (-5925 3575)(-5775 3575);
WIRE 16 -1 (-5775 3575)(-5775 3525);
WIRE 16 -1 (-5925 3525)(-5775 3525);
WIRE 16 -1 (-5775 3525)(-5775 3475);
WIRE 16 -1 (-5925 3475)(-5775 3475);
WIRE 16 -1 (-5775 3475)(-5775 3375);
WIRE 16 -1 (-5925 3375)(-5775 3375);
WIRE 16 -1 (-5775 3375)(-5775 3325);
WIRE 16 -1 (-5925 3325)(-5775 3325);
WIRE 16 -1 (-5775 3325)(-5775 3275);
WIRE 16 -1 (-5925 3275)(-5775 3275);
WIRE 16 -1 (-5775 3275)(-5775 3225);
WIRE 16 -1 (-5925 3225)(-5775 3225);
WIRE 16 -1 (-5775 3225)(-5775 3175);
WIRE 16 -1 (-5925 3175)(-5775 3175);
WIRE 16 -1 (-5775 3175)(-5775 3125);
WIRE 16 -1 (-5925 3125)(-5775 3125);
WIRE 16 -1 (-5775 3125)(-5775 2925);
WIRE 16 -1 (-5925 2925)(-5775 2925);
WIRE 16 -1 (-5775 2925)(-5775 2575);
WIRE 16 -1 (-5925 2575)(-5775 2575);
WIRE 16 -1 (-5775 2575)(-5775 2325);
WIRE 16 -1 (-5925 2325)(-5775 2325);
WIRE 16 -1 (-5125 2325)(-5775 2325);
WIRE 16 -1 (-5125 2325)(-5125 2275);
WIRE 16 -1 (-5925 2275)(-5125 2275);
WIRE 16 -1 (-5125 2225)(-5125 2275);
WIRE 16 -1 (-6725 1125)(-6850 1125);
WIRE 16 -1 (-6850 1125)(-6850 1175);
WIRE 16 -1 (-6725 1175)(-6850 1175);
WIRE 16 -1 (-6850 1175)(-6850 1225);
WIRE 16 -1 (-6725 1225)(-6850 1225);
WIRE 16 -1 (-6850 1225)(-6850 1275);
WIRE 16 -1 (-6725 1275)(-6850 1275);
WIRE 16 -1 (-6850 1275)(-6850 1375);
WIRE 16 -1 (-6725 1375)(-6850 1375);
WIRE 16 -1 (-6850 1375)(-6850 1425);
WIRE 16 -1 (-6725 1425)(-6850 1425);
WIRE 16 -1 (-6850 1425)(-6850 1475);
WIRE 16 -1 (-6725 1475)(-6850 1475);
WIRE 16 -1 (-6850 1525)(-6850 1475);
WIRE 16 -1 (-6725 1525)(-6850 1525);
WIRE 16 -1 (-6850 1525)(-6850 1550);
WIRE 16 -1 (-6850 1550)(-6850 1575);
WIRE 16 -1 (-7125 1550)(-6850 1550);
WIRE 16 -1 (-7125 1550)(-7125 1475);
WIRE 16 -1 (-6850 1575)(-6850 1625);
WIRE 16 -1 (-6725 1575)(-6850 1575);
WIRE 16 -1 (-6850 1625)(-6850 1825);
WIRE 16 -1 (-6725 1625)(-6850 1625);
WIRE 16 -1 (-6850 1825)(-6850 1875);
WIRE 16 -1 (-6725 1825)(-6850 1825);
WIRE 16 -1 (-6725 1875)(-6850 1875);
WIRE 16 -1 (-7925 4225)(-6725 4225);
FORCEPROP 2 LAST SIG_NAME FM_CPU1_VRM_322M_156M_OSC_EN
J 0
(-7900 4235);
DISPLAY 0.617021 (-7900 4235);
PAINT ORANGE (-7900 4235);
WIRE 16 -1 (-6725 1075)(-7950 1075);
FORCEPROP 2 LAST SIG_NAME VR_PVCCIOMCP_CPU1_XADDR1
J 0
(-7490 1090);
DISPLAY 0.617021 (-7490 1090);
PAINT ORANGE (-7490 1090);
FORCEPROP 2 LASTPROP $XRERR UNIQUE?
J 0
(-7730 1090);
DISPLAY 0.638298 (-7730 1090);
PAINT MONO (-7730 1090);
DISPLAY INVISIBLE (-7730 1090);
WIRE 16 -1 (-7950 875)(-7950 1075);
WIRE 16 -1 (-7600 1025)(-6725 1025);
FORCEPROP 2 LAST SIG_NAME VR_PVCCMCP_CPU1_XADDR2
J 0
(-7490 1040);
DISPLAY 0.617021 (-7490 1040);
PAINT ORANGE (-7490 1040);
FORCEPROP 2 LASTPROP $XRERR UNIQUE?
J 0
(-7730 1040);
DISPLAY 0.638298 (-7730 1040);
PAINT MONO (-7730 1040);
DISPLAY INVISIBLE (-7730 1040);
WIRE 16 -1 (-7600 1025)(-7600 850);
WIRE 16 -1 (-7625 1775)(-6725 1775);
FORCEPROP 2 LAST SIG_NAME VSENSE_PVCCIOMCP_CPU1_SKT_VSEN
J 0
(-7635 1785);
DISPLAY 0.617021 (-7635 1785);
PAINT ORANGE (-7635 1785);
WIRE 16 -1 (-7625 1725)(-6725 1725);
FORCEPROP 2 LAST SIG_NAME VSENSE_PVCCIOMCP_CPU1_SKT_VRTN
J 0
(-7635 1735);
DISPLAY 0.617021 (-7635 1735);
PAINT ORANGE (-7635 1735);
WIRE 16 -1 (-5925 1625)(-5200 1625);
FORCEPROP 2 LAST SIG_NAME SVID_ALERT0_CPU1_R_N
J 0
(-5800 1635);
DISPLAY 0.617021 (-5800 1635);
PAINT ORANGE (-5800 1635);
WIRE 16 -1 (-5925 1075)(-5150 1075);
FORCEPROP 0 LAST SIG_NAME SVID_CLK1_CPU1_R
J 0
(-5775 1085);
DISPLAY 0.617021 (-5775 1085);
PAINT ORANGE (-5775 1085);
WIRE 16 -1 (-5925 1025)(-5150 1025);
FORCEPROP 2 LAST SIG_NAME SVID_DIO1_CPU1_R
J 0
(-5775 1035);
DISPLAY 0.617021 (-5775 1035);
PAINT ORANGE (-5775 1035);
WIRE 16 -1 (-5925 1175)(-5125 1175);
FORCEPROP 2 LAST SIG_NAME FM_PVCCMCP_CPU1_EN
J 0
(-5775 1185);
DISPLAY 0.617021 (-5775 1185);
PAINT ORANGE (-5775 1185);
WIRE 16 -1 (-5925 1125)(-5125 1125);
FORCEPROP 2 LAST SIG_NAME PWRGD_PVCCMCP_CPU1
J 0
(-5765 1140);
DISPLAY 0.617021 (-5765 1140);
PAINT ORANGE (-5765 1140);
WIRE 16 -1 (-5925 1575)(-5200 1575);
FORCEPROP 2 LAST SIG_NAME SVID_ALERT1_CPU1_R_N
J 0
(-5800 1585);
DISPLAY 0.617021 (-5800 1585);
PAINT ORANGE (-5800 1585);
WIRE 16 -1 (-5925 1225)(-5150 1225);
FORCEPROP 2 LAST SIG_NAME SVID_DIO0_CPU1_R
J 0
(-5775 1235);
DISPLAY 0.617021 (-5775 1235);
PAINT ORANGE (-5775 1235);
WIRE 16 -1 (-5925 1925)(-5200 1925);
FORCEPROP 2 LAST SIG_NAME SMB_VR_STBY_LVC3_SDA
J 0
(-5815 1940);
DISPLAY 0.617021 (-5815 1940);
PAINT ORANGE (-5815 1940);
WIRE 16 -1 (-5925 1975)(-5200 1975);
FORCEPROP 2 LAST SIG_NAME SMB_VR_STBY_LVC3_SCL
J 0
(-5815 1990);
DISPLAY 0.617021 (-5815 1990);
PAINT ORANGE (-5815 1990);
WIRE 16 -1 (-5925 1275)(-5150 1275);
FORCEPROP 0 LAST SIG_NAME SVID_CLK0_CPU1_R
J 0
(-5775 1285);
DISPLAY 0.617021 (-5775 1285);
PAINT ORANGE (-5775 1285);
WIRE 16 -1 (-5925 2675)(-5175 2675);
FORCEPROP 2 LAST SIG_NAME FM_PVCCIOMCP_CPU1_EN
J 0
(-5750 2685);
DISPLAY 0.617021 (-5750 2685);
PAINT ORANGE (-5750 2685);
WIRE 16 -1 (-5925 2625)(-5150 2625);
FORCEPROP 2 LAST SIG_NAME PWRGD_PVCCIOMCP_CPU1
J 0
(-5765 2640);
DISPLAY 0.617021 (-5765 2640);
PAINT ORANGE (-5765 2640);
WIRE 16 -1 (-5925 3025)(-5150 3025);
FORCEPROP 2 LAST SIG_NAME FM_P1V8MCP_CPU1_EN
J 0
(-5750 3035);
DISPLAY 0.617021 (-5750 3035);
PAINT ORANGE (-5750 3035);
WIRE 16 -1 (-5925 2975)(-5125 2975);
FORCEPROP 2 LAST SIG_NAME PWRGD_P1V8MCP_CPU1
J 0
(-5765 2990);
DISPLAY 0.617021 (-5765 2990);
PAINT ORANGE (-5765 2990);
WIRE 16 -1 (-3550 2850)(-4725 2850);
FORCEPROP 2 LAST SIG_NAME CLK_322M_156M_CPU1_OSC_VRM_DN
J 0
(-4685 2860);
DISPLAY 0.617021 (-4685 2860);
PAINT ORANGE (-4685 2860);
WIRE 16 -1 (-3550 2900)(-4725 2900);
FORCEPROP 2 LAST SIG_NAME CLK_322M_156M_CPU1_OSC_VRM_DP
J 0
(-4685 2910);
DISPLAY 0.617021 (-4685 2910);
PAINT ORANGE (-4685 2910);
WIRE 16 -1 (-4775 4350)(-3550 4350);
FORCEPROP 2 LAST SIG_NAME VSENSE_P1V8MCP_CPU1_SKT_VSEN
J 0
(-4790 4370);
DISPLAY 0.617021 (-4790 4370);
PAINT ORANGE (-4790 4370);
WIRE 16 -1 (-4725 4000)(-3550 4000);
FORCEPROP 2 LAST SIG_NAME VSENSE_P1V8MCP_CPU1_SKT_VRTN
J 0
(-4715 4020);
DISPLAY 0.617021 (-4715 4020);
PAINT ORANGE (-4715 4020);
WIRE 16 -1 (-4700 3400)(-3550 3400);
FORCEPROP 2 LAST SIG_NAME VSENSE_PVCCMCP_CPU1_SKT_VRTN
J 0
(-4690 3420);
DISPLAY 0.617021 (-4690 3420);
PAINT ORANGE (-4690 3420);
WIRE 16 -1 (-4700 3450)(-3550 3450);
FORCEPROP 2 LAST SIG_NAME VSENSE_PVCCMCP_CPU1_SKT_VSEN
J 0
(-4715 3470);
DISPLAY 0.617021 (-4715 3470);
PAINT ORANGE (-4715 3470);
DOT 1 (-6850 1375);
DOT 1 (-6850 1550);
DOT 1 (-6850 1575);
DOT 1 (-6850 1475);
DOT 1 (-3725 1650);
DOT 1 (-1525 2750);
DOT 1 (-1550 3175);
DOT 1 (-6950 4425);
DOT 1 (-2300 2000);
DOT 1 (-2300 2050);
DOT 1 (-2300 2300);
DOT 1 (-3975 3550);
DOT 1 (-3975 3600);
DOT 1 (-3975 3300);
DOT 1 (-6850 1175);
DOT 1 (-6850 1225);
DOT 1 (-6850 1275);
DOT 1 (-6850 1425);
DOT 1 (-3850 4300);
DOT 1 (-3850 3950);
DOT 1 (-3850 4250);
DOT 1 (-3975 2150);
DOT 1 (-3975 2500);
DOT 1 (-2150 1100);
DOT 1 (-2150 1150);
DOT 1 (-2150 1200);
DOT 1 (-2150 1250);
DOT 1 (-2150 1300);
DOT 1 (-2150 1350);
DOT 1 (-1225 1625);
DOT 1 (-1225 2100);
DOT 1 (-1150 3975);
DOT 1 (-1150 4450);
DOT 1 (-5525 4425);
DOT 1 (-5525 4375);
DOT 1 (-5775 4225);
DOT 1 (-5775 4175);
DOT 1 (-6950 4375);
DOT 1 (-5500 3675);
DOT 1 (-5500 3725);
DOT 1 (-5775 4075);
DOT 1 (-5775 4025);
DOT 1 (-5775 3975);
DOT 1 (-5775 3925);
DOT 1 (-5775 3875);
DOT 1 (-5775 3825);
DOT 1 (-5775 3575);
DOT 1 (-5775 3525);
DOT 1 (-5775 3475);
DOT 1 (-5775 3375);
DOT 1 (-5775 3225);
DOT 1 (-5775 3125);
DOT 1 (-5775 3175);
DOT 1 (-5250 2875);
DOT 1 (-5250 2825);
DOT 1 (-5250 2775);
DOT 1 (-5250 2475);
DOT 1 (-5250 2525);
DOT 1 (-5250 2425);
DOT 1 (-5125 2275);
DOT 1 (-5250 2225);
DOT 1 (-5250 2125);
DOT 1 (-5250 2175);
DOT 1 (-5250 2075);
DOT 1 (-5775 2575);
DOT 1 (-5775 2925);
DOT 1 (-5775 2325);
DOT 1 (-5250 1825);
DOT 1 (-5250 1875);
DOT 1 (-5250 1775);
DOT 1 (-5250 1725);
DOT 1 (-5250 1475);
DOT 1 (-5250 1425);
DOT 1 (-6950 4075);
DOT 1 (-6950 4025);
DOT 1 (-7150 3875);
DOT 1 (-6950 3725);
DOT 1 (-6950 3675);
DOT 1 (-7150 3625);
DOT 1 (-7150 3825);
DOT 1 (-6950 3375);
DOT 1 (-7150 3575);
DOT 1 (-7150 3525);
DOT 1 (-7150 3475);
DOT 1 (-6950 3325);
DOT 1 (-7150 3275);
DOT 1 (-7150 3225);
DOT 1 (-7150 3125);
DOT 1 (-7150 3175);
DOT 1 (-6950 2975);
DOT 1 (-6950 3025);
DOT 1 (-7150 2925);
DOT 1 (-7150 2875);
DOT 1 (-7150 2825);
DOT 1 (-6950 2675);
DOT 1 (-6950 2625);
DOT 1 (-7150 2575);
DOT 1 (-7150 2775);
DOT 1 (-6950 2325);
DOT 1 (-7150 2475);
DOT 1 (-7150 2525);
DOT 1 (-7150 2425);
DOT 1 (-6950 2275);
DOT 1 (-7150 2225);
DOT 1 (-7150 2175);
DOT 1 (-7150 2125);
DOT 1 (-7150 2075);
DOT 1 (-6850 1825);
DOT 1 (-6850 1625);
DOT 1 (-6950 1975);
DOT 1 (-6850 1525);
DOT 1 (-2300 4500);
DOT 1 (-2300 4450);
DOT 1 (-2300 4400);
DOT 1 (-2150 4300);
DOT 1 (-2150 4250);
DOT 1 (-2300 4150);
DOT 1 (-2300 4100);
DOT 1 (-2150 4000);
DOT 1 (-2150 3900);
DOT 1 (-2150 3950);
DOT 1 (-2300 4050);
DOT 1 (-2150 3600);
DOT 1 (-2150 3650);
DOT 1 (-2300 3750);
DOT 1 (-2300 3800);
DOT 1 (-2300 3700);
DOT 1 (-2150 3550);
DOT 1 (-2300 3450);
DOT 1 (-2300 3400);
DOT 1 (-2300 3350);
DOT 1 (-2150 3250);
DOT 1 (-2150 3300);
DOT 1 (-2150 3200);
DOT 1 (-2300 3100);
DOT 1 (-2150 2950);
DOT 1 (-2150 2900);
DOT 1 (-2150 2850);
DOT 1 (-2300 3000);
DOT 1 (-2300 3050);
DOT 1 (-2150 2600);
DOT 1 (-2300 2750);
DOT 1 (-2300 2700);
DOT 1 (-2300 2650);
DOT 1 (-2150 2500);
DOT 1 (-2150 2550);
DOT 1 (-2300 2350);
DOT 1 (-2300 2400);
DOT 1 (-2150 2250);
DOT 1 (-2150 2200);
DOT 1 (-2150 2150);
DOT 1 (-1700 2050);
DOT 1 (-1700 1650);
DOT 1 (-2150 1850);
DOT 1 (-2150 1900);
DOT 1 (-2150 1800);
DOT 1 (-2150 1700);
DOT 1 (-2150 1650);
DOT 1 (-2150 1600);
DOT 1 (-2150 1550);
DOT 1 (-2150 1500);
DOT 1 (-2150 1450);
DOT 1 (-3725 4500);
DOT 1 (-3725 4450);
DOT 1 (-3725 4400);
DOT 1 (-3725 4150);
DOT 1 (-3725 4100);
DOT 1 (-3725 4050);
DOT 1 (-3725 3800);
DOT 1 (-3725 3750);
DOT 1 (-3725 3350);
DOT 1 (-3725 3100);
DOT 1 (-3975 3250);
DOT 1 (-3725 3000);
DOT 1 (-3725 3050);
DOT 1 (-3725 2750);
DOT 1 (-3725 2700);
DOT 1 (-3725 2650);
DOT 1 (-3725 2350);
DOT 1 (-3725 2400);
DOT 1 (-3725 2300);
DOT 1 (-3975 2950);
DOT 1 (-3975 2600);
DOT 1 (-3975 2550);
DOT 1 (-3975 2250);
DOT 1 (-3975 2200);
DOT 1 (-3725 2050);
DOT 1 (-3725 1950);
DOT 1 (-3725 2000);
DOT 1 (-3725 1700);
DOT 1 (-3725 1600);
DOT 1 (-3725 1350);
DOT 1 (-3725 1300);
DOT 1 (-3975 1900);
DOT 1 (-3975 1850);
DOT 1 (-3975 1800);
DOT 1 (-3975 1550);
DOT 1 (-3975 1450);
DOT 1 (-3975 1500);
DOT 1 (-3975 1200);
DOT 1 (-3975 1100);
DOT 1 (-3975 1150);
DOT 1 (-7750 525);
DOT 1 (-7150 3975);
DOT 1 (-7150 3925);
DOT 1 (-3975 3200);
DOT 1 (-5775 3325);
DOT 1 (-5775 3275);
DOT 1 (-5250 1525);
FORCENOTE
SMBUS ADDRESS: VCCMCP 0XB8, VCCIOMCP/P1V8MCP 0XC8 
(-7275 450) 0;
DISPLAY LEFT (-7275 450);
DISPLAY 1.021277 (-7275 450);
PAINT PURPLE (-7275 450);
FORCENOTE
DEBUG ONLY
(-5900 4803) 0;
DISPLAY LEFT (-5900 4803);
DISPLAY 3.851064 (-5900 4803);
PAINT PURPLE (-5900 4803);
FORCENOTE
ROOM=PVCCP_MCP_CPU1
(-1650 3628) 0;
DISPLAY LEFT (-1650 3628);
PAINT PURPLE (-1650 3628);
QUIT
